FILE_TYPE = MACRO_DRAWING;
SET COLOR_WIRE YELLOW;
SET COLOR_PROP MONO;
SET COLOR_DOT WHITE;
SET COLOR_ARC YELLOW;
SET COLOR_BODY GREEN;
SET COLOR_NOTE MONO;
SET PROP_DISPLAY VALUE;
SET PAGE_NUMBER P222;
FORCEADD GND..1
(-1150 -1075);
FORCEPROP 3 LASTPIN (-1150 -1025) SIG_NAME GND\g
J 0
(-1140 -1015);
DISPLAY 0.659574 (-1140 -1015);
PAINT MONO (-1140 -1015);
DISPLAY INVISIBLE (-1140 -1015);
FORCEPROP 1 LAST PATH I1
J 0
(-1075 -1075);
DISPLAY 0.872340 (-1075 -1075);
PAINT AQUA (-1075 -1075);
DISPLAY INVISIBLE (-1075 -1075);
FORCEPROP 1 LAST VOLTAGE 0.0V
J 0
(-1195 -1118);
DISPLAY 0.340426 (-1195 -1118);
PAINT SKYBLUE (-1195 -1118);
DISPLAY INVISIBLE (-1195 -1118);
FORCEPROP 1 LAST SIZE 1B
J 0
(-1075 -1125);
DISPLAY 0.893617 (-1075 -1125);
PAINT GREEN (-1075 -1125);
DISPLAY INVISIBLE (-1075 -1125);
FORCEPROP 2 LAST CDS_LIB mstr_symbols
J 0
(-1150 -1075);
PAINT MONO (-1150 -1075);
DISPLAY INVISIBLE (-1150 -1075);
FORCEPROP 1 LAST BODY_TYPE PLUMBING
J 0
(-1195 -1118);
DISPLAY 0.340426 (-1195 -1118);
PAINT GREEN (-1195 -1118);
DISPLAY INVISIBLE (-1195 -1118);
FORCEPROP 1 LAST HDL_POWER GND
J 0
(-1150 -925);
DISPLAY 0.893617 (-1150 -925);
PAINT GREEN (-1150 -925);
DISPLAY INVISIBLE (-1150 -925);
FORCEADD RES..1
(-650 1300);
FORCEPROP 1 LAST PACK_TYPE 0402
J 0
(-725 1100);
DISPLAY 0.617021 (-725 1100);
PAINT SKYBLUE (-725 1100);
FORCEPROP 1 LAST MATERIAL CHIP
J 0
(-650 1150);
DISPLAY 0.617021 (-650 1150);
PAINT SKYBLUE (-650 1150);
FORCEPROP 1 LAST WATTAGE 1/16W
J 2
(-675 1150);
DISPLAY 0.617021 (-675 1150);
PAINT SKYBLUE (-675 1150);
FORCEPROP 1 LAST VALUE 0.0
J 2
(-675 1200);
DISPLAY 0.617021 (-675 1200);
PAINT SKYBLUE (-675 1200);
FORCEPROP 1 LAST TOLERANCE 5%
J 0
(-650 1200);
DISPLAY 0.617021 (-650 1200);
PAINT SKYBLUE (-650 1200);
FORCEPROP 1 LAST PART_NUMBER G21497-005
J 0
(-775 1250);
DISPLAY 0.617021 (-775 1250);
PAINT BLUE (-775 1250);
FORCEPROP 1 LASTPIN (-550 1300) $PN 2
J 0
(-588 1312);
DISPLAY 0.617021 (-588 1312);
PAINT WHITE (-588 1312);
FORCEPROP 1 LASTPIN (-750 1300) $PN 1
J 0
(-738 1312);
DISPLAY 0.617021 (-738 1312);
PAINT WHITE (-738 1312);
FORCEPROP 1 LAST LOCATION R6L11
J 0
(-700 1350);
DISPLAY 0.617021 (-700 1350);
PAINT AQUA (-700 1350);
FORCEPROP 1 LAST PATH I10
J 0
(-700 1450);
DISPLAY 0.978723 (-700 1450);
PAINT WHITE (-700 1450);
DISPLAY INVISIBLE (-700 1450);
FORCEPROP 0 LAST CDS_SEC 1
J 0
(-700 1400);
PAINT MONO (-700 1400);
DISPLAY INVISIBLE (-700 1400);
FORCEPROP 2 LAST ROOM VTT_DEF_PWR_VR
J 0
(-690 1385);
DISPLAY 1.021277 (-690 1385);
PAINT ORANGE (-690 1385);
DISPLAY INVISIBLE (-690 1385);
FORCEPROP 2 LAST BOM_COST MEM_VRD_VTT_DEF
J 0
(-690 1435);
DISPLAY 1.021277 (-690 1435);
PAINT ORANGE (-690 1435);
DISPLAY INVISIBLE (-690 1435);
FORCEPROP 2 LAST CDS_LOCATION R6L11
J 0
(-700 1350);
DISPLAY 0.617021 (-700 1350);
PAINT AQUA (-700 1350);
DISPLAY INVISIBLE (-700 1350);
FORCEPROP 2 LAST CDS_LIB mstr_discrete
J 0
(-650 1300);
DISPLAY 0.744681 (-650 1300);
PAINT MONO (-650 1300);
DISPLAY INVISIBLE (-650 1300);
FORCEPROP 2 LAST SEC_TYPE 0402
J 0
(-684 1500);
DISPLAY 1.021277 (-684 1500);
PAINT ORANGE (-684 1500);
DISPLAY INVISIBLE (-684 1500);
FORCEPROP 2 LAST SEC 1
J 0
(-684 1500);
DISPLAY 0.680851 (-684 1500);
PAINT MONO (-684 1500);
DISPLAY INVISIBLE (-684 1500);
FORCEADD GND..1
(-325 800);
FORCEPROP 3 LASTPIN (-325 850) SIG_NAME GND\g
J 0
(-315 860);
DISPLAY 0.659574 (-315 860);
PAINT MONO (-315 860);
DISPLAY INVISIBLE (-315 860);
FORCEPROP 1 LAST PATH I11
J 0
(-250 800);
DISPLAY 0.872340 (-250 800);
PAINT AQUA (-250 800);
DISPLAY INVISIBLE (-250 800);
FORCEPROP 2 LAST CDS_LIB mstr_symbols
J 0
(-325 800);
DISPLAY 0.744681 (-325 800);
PAINT MONO (-325 800);
DISPLAY INVISIBLE (-325 800);
FORCEPROP 1 LAST VOLTAGE 0.0V
J 0
(-370 757);
DISPLAY 0.340426 (-370 757);
PAINT SKYBLUE (-370 757);
DISPLAY INVISIBLE (-370 757);
FORCEPROP 1 LAST SIZE 1B
J 0
(-250 750);
DISPLAY 0.893617 (-250 750);
PAINT GREEN (-250 750);
DISPLAY INVISIBLE (-250 750);
FORCEPROP 1 LAST BODY_TYPE PLUMBING
J 0
(-370 757);
DISPLAY 0.340426 (-370 757);
PAINT GREEN (-370 757);
DISPLAY INVISIBLE (-370 757);
FORCEPROP 1 LAST HDL_POWER GND
J 0
(-325 950);
DISPLAY 0.893617 (-325 950);
PAINT GREEN (-325 950);
DISPLAY INVISIBLE (-325 950);
FORCEADD CAP..1
(-325 1050);
FORCEPROP 1 LAST PACK_TYPE 0402
J 0
(-275 950);
DISPLAY 0.617021 (-275 950);
PAINT SKYBLUE (-275 950);
FORCEPROP 1 LAST PART_NUMBER D97712-011
J 0
(-275 1000);
DISPLAY 0.617021 (-275 1000);
PAINT BLUE (-275 1000);
FORCEPROP 1 LAST TOLERANCE 10%
J 0
(-275 1050);
DISPLAY 0.617021 (-275 1050);
PAINT SKYBLUE (-275 1050);
FORCEPROP 1 LAST MATERIAL X6S
J 0
(-150 1050);
DISPLAY 0.617021 (-150 1050);
PAINT SKYBLUE (-150 1050);
FORCEPROP 1 LAST VALUE 1.0UF
J 0
(-275 1100);
DISPLAY 0.617021 (-275 1100);
PAINT SKYBLUE (-275 1100);
FORCEPROP 1 LAST LOCATION C4A10
J 0
(-275 1150);
DISPLAY 0.617021 (-275 1150);
PAINT AQUA (-275 1150);
FORCEPROP 1 LAST VOLTAGE 16V
J 0
(-125 1100);
DISPLAY 0.617021 (-125 1100);
PAINT SKYBLUE (-125 1100);
FORCEPROP 1 LASTPIN (-325 950) $PN 2
J 0
(-315 930);
DISPLAY 0.617021 (-315 930);
PAINT WHITE (-315 930);
FORCEPROP 1 LASTPIN (-325 1150) $PN 1
J 0
(-315 1130);
DISPLAY 0.617021 (-315 1130);
PAINT WHITE (-315 1130);
FORCEPROP 1 LAST PATH I12
J 0
(-275 1200);
DISPLAY 0.978723 (-275 1200);
PAINT WHITE (-275 1200);
DISPLAY INVISIBLE (-275 1200);
FORCEPROP 0 LAST CDS_SEC 1
J 0
(-275 1200);
PAINT MONO (-275 1200);
DISPLAY INVISIBLE (-275 1200);
FORCEPROP 2 LAST CDS_LOCATION C4A10
J 0
(-275 1150);
DISPLAY 0.617021 (-275 1150);
PAINT AQUA (-275 1150);
DISPLAY INVISIBLE (-275 1150);
FORCEPROP 2 LAST CDS_LIB mstr_discrete
J 0
(-325 1050);
PAINT ORANGE (-325 1050);
DISPLAY INVISIBLE (-325 1050);
FORCEPROP 2 LAST ROOM VTT_DEF_PWR_VR
J 0
(-275 1200);
DISPLAY 1.021277 (-275 1200);
PAINT ORANGE (-275 1200);
DISPLAY INVISIBLE (-275 1200);
FORCEPROP 2 LAST BOM_COST MEM_VRD_VTT_DEF
J 0
(-275 1250);
DISPLAY 1.021277 (-275 1250);
PAINT ORANGE (-275 1250);
DISPLAY INVISIBLE (-275 1250);
FORCEPROP 2 LAST SEC_TYPE 0402
J 0
(-275 1246);
DISPLAY 1.021277 (-275 1246);
PAINT ORANGE (-275 1246);
DISPLAY INVISIBLE (-275 1246);
FORCEPROP 2 LAST SEC 1
J 0
(-275 1246);
DISPLAY 0.680851 (-275 1246);
PAINT MONO (-275 1246);
DISPLAY INVISIBLE (-275 1246);
FORCEADD MIC5166..1
(775 600);
FORCEPROP 2 LASTPIN (1075 400) $PN 3
J 0
(1085 410);
DISPLAY 0.617021 (1085 410);
PAINT ORANGE (1085 410);
FORCEPROP 1 LAST PART_NUMBER H55101-001
J 0
(525 200);
DISPLAY 0.617021 (525 200);
PAINT BLUE (525 200);
FORCEPROP 2 LASTPIN (475 500) $PN 6
J 2
(465 510);
DISPLAY 0.617021 (465 510);
PAINT ORANGE (465 510);
FORCEPROP 2 LASTPIN (1075 850) $PN 9
J 0
(1085 860);
DISPLAY 0.617021 (1085 860);
PAINT ORANGE (1085 860);
FORCEPROP 2 LASTPIN (475 350) $PN 2
J 2
(465 360);
DISPLAY 0.617021 (465 360);
PAINT ORANGE (465 360);
FORCEPROP 2 LASTPIN (1075 450) $PN 8
J 0
(1085 460);
DISPLAY 0.617021 (1085 460);
PAINT ORANGE (1085 460);
FORCEPROP 2 LASTPIN (475 600) $PN 7
J 2
(465 610);
DISPLAY 0.617021 (465 610);
PAINT ORANGE (465 610);
FORCEPROP 2 LASTPIN (475 850) $PN 10
J 2
(465 860);
DISPLAY 0.617021 (465 860);
PAINT ORANGE (465 860);
FORCEPROP 1 LAST MATERIAL IC
J 0
(525 975);
DISPLAY 0.617021 (525 975);
PAINT SKYBLUE (525 975);
FORCEPROP 1 LAST LOCATION EU4A1
J 0
(525 1025);
DISPLAY 0.617021 (525 1025);
PAINT AQUA (525 1025);
FORCEPROP 2 LASTPIN (1075 750) $PN 1
J 0
(1085 760);
DISPLAY 0.617021 (1085 760);
PAINT ORANGE (1085 760);
FORCEPROP 2 LASTPIN (1075 550) $PN 5
J 0
(1085 560);
DISPLAY 0.617021 (1085 560);
PAINT ORANGE (1085 560);
FORCEPROP 2 LASTPIN (1075 300) $PN 11
J 0
(1085 310);
DISPLAY 0.617021 (1085 310);
PAINT ORANGE (1085 310);
FORCEPROP 2 LASTPIN (475 700) $PN 4
J 2
(465 710);
DISPLAY 0.617021 (465 710);
PAINT ORANGE (465 710);
FORCEPROP 1 LAST PATH I13
J 0
(975 975);
PAINT GREEN (975 975);
DISPLAY INVISIBLE (975 975);
FORCEPROP 0 LAST CDS_SEC 1
J 0
(525 1075);
PAINT MONO (525 1075);
DISPLAY INVISIBLE (525 1075);
FORCEPROP 2 LAST BOM_COST MEM_VRD_VTT_DEF
J 0
(525 1120);
DISPLAY 1.021277 (525 1120);
PAINT ORANGE (525 1120);
DISPLAY INVISIBLE (525 1120);
FORCEPROP 1 LAST PACK_TYPE DFN
J 0
(525 1075);
PAINT SKYBLUE (525 1075);
DISPLAY INVISIBLE (525 1075);
FORCEPROP 2 LAST SEC_TYPE DFN
J 0
(533 1072);
DISPLAY 1.021277 (533 1072);
PAINT ORANGE (533 1072);
DISPLAY INVISIBLE (533 1072);
FORCEPROP 2 LAST SEC 1
J 0
(533 1072);
DISPLAY 0.680851 (533 1072);
PAINT MONO (533 1072);
DISPLAY INVISIBLE (533 1072);
FORCEPROP 2 LAST CDS_LOCATION EU4A1
J 0
(525 1025);
DISPLAY 0.617021 (525 1025);
PAINT AQUA (525 1025);
DISPLAY INVISIBLE (525 1025);
FORCEPROP 2 LAST ROOM VTT_DEF_PWR_VR
J 0
(525 1072);
DISPLAY 1.021277 (525 1072);
PAINT ORANGE (525 1072);
DISPLAY INVISIBLE (525 1072);
FORCEPROP 1 LAST CDS_LMAN_SYM_OUTLINE -250,350,250,-350
J 0
(775 600);
DISPLAY 0.468085 (775 600);
PAINT GREEN (775 600);
DISPLAY INVISIBLE (775 600);
FORCEPROP 2 LAST CDS_LIB mstr_vreg
J 0
(775 600);
PAINT ORANGE (775 600);
DISPLAY INVISIBLE (775 600);
FORCEADD GND..1
(-750 1650);
FORCEPROP 3 LASTPIN (-750 1700) SIG_NAME GND\g
J 0
(-740 1710);
DISPLAY 0.659574 (-740 1710);
PAINT MONO (-740 1710);
DISPLAY INVISIBLE (-740 1710);
FORCEPROP 1 LAST PATH I14
J 0
(-675 1650);
DISPLAY 0.872340 (-675 1650);
PAINT AQUA (-675 1650);
DISPLAY INVISIBLE (-675 1650);
FORCEPROP 2 LAST BOM_COST MEM_VRD_VTT_DEF
J 0
(-1255 1780);
DISPLAY 1.021277 (-1255 1780);
PAINT ORANGE (-1255 1780);
DISPLAY INVISIBLE (-1255 1780);
FORCEPROP 2 LAST ROOM VTT_DEF_PWR_VR
J 0
(-1255 1730);
DISPLAY 1.021277 (-1255 1730);
PAINT ORANGE (-1255 1730);
DISPLAY INVISIBLE (-1255 1730);
FORCEPROP 1 LAST VOLTAGE 0.0V
J 0
(-795 1607);
DISPLAY 0.340426 (-795 1607);
PAINT SKYBLUE (-795 1607);
DISPLAY INVISIBLE (-795 1607);
FORCEPROP 1 LAST SIZE 1B
J 0
(-675 1600);
DISPLAY 0.893617 (-675 1600);
PAINT GREEN (-675 1600);
DISPLAY INVISIBLE (-675 1600);
FORCEPROP 2 LAST CDS_LIB mstr_symbols
J 0
(-750 1650);
DISPLAY 0.744681 (-750 1650);
PAINT MONO (-750 1650);
DISPLAY INVISIBLE (-750 1650);
FORCEPROP 1 LAST BODY_TYPE PLUMBING
J 0
(-795 1607);
DISPLAY 0.340426 (-795 1607);
PAINT GREEN (-795 1607);
DISPLAY INVISIBLE (-795 1607);
FORCEPROP 1 LAST HDL_POWER GND
J 0
(-750 1800);
DISPLAY 0.893617 (-750 1800);
PAINT GREEN (-750 1800);
DISPLAY INVISIBLE (-750 1800);
FORCEADD CAP..1
(-750 1900);
FORCEPROP 1 LAST PART_NUMBER E15431-001
J 0
(-700 1750);
DISPLAY 0.617021 (-700 1750);
PAINT BLUE (-700 1750);
FORCEPROP 1 LAST PACK_TYPE 0603LF
J 0
(-700 1700);
DISPLAY 0.617021 (-700 1700);
PAINT SKYBLUE (-700 1700);
FORCEPROP 1 LAST MATERIAL X6S
J 0
(-700 1800);
DISPLAY 0.617021 (-700 1800);
PAINT SKYBLUE (-700 1800);
FORCEPROP 1 LAST TOLERANCE 20%
J 0
(-700 1850);
DISPLAY 0.617021 (-700 1850);
PAINT SKYBLUE (-700 1850);
FORCEPROP 1 LAST LOCATION C6L4
J 0
(-700 2000);
DISPLAY 0.617021 (-700 2000);
PAINT AQUA (-700 2000);
FORCEPROP 1 LAST VALUE 10UF
J 0
(-700 1950);
DISPLAY 0.617021 (-700 1950);
PAINT SKYBLUE (-700 1950);
FORCEPROP 1 LAST VOLTAGE 4V
J 0
(-700 1900);
DISPLAY 0.617021 (-700 1900);
PAINT SKYBLUE (-700 1900);
FORCEPROP 1 LASTPIN (-750 1800) $PN 2
J 0
(-740 1780);
DISPLAY 0.617021 (-740 1780);
PAINT WHITE (-740 1780);
FORCEPROP 1 LASTPIN (-750 2000) $PN 1
J 0
(-740 1980);
DISPLAY 0.617021 (-740 1980);
PAINT WHITE (-740 1980);
FORCEPROP 1 LAST PATH I15
J 0
(-700 2050);
DISPLAY 0.978723 (-700 2050);
PAINT WHITE (-700 2050);
DISPLAY INVISIBLE (-700 2050);
FORCEPROP 0 LAST CDS_SEC 1
J 0
(-700 2050);
PAINT MONO (-700 2050);
DISPLAY INVISIBLE (-700 2050);
FORCEPROP 2 LAST CDS_LIB mstr_discrete
J 0
(-750 1900);
PAINT ORANGE (-750 1900);
DISPLAY INVISIBLE (-750 1900);
FORCEPROP 2 LAST CDS_LOCATION C6L4
J 0
(-700 2000);
DISPLAY 0.617021 (-700 2000);
PAINT AQUA (-700 2000);
DISPLAY INVISIBLE (-700 2000);
FORCEPROP 2 LAST SEC_TYPE 0603LF
J 0
(-694 2115);
DISPLAY 1.021277 (-694 2115);
PAINT ORANGE (-694 2115);
DISPLAY INVISIBLE (-694 2115);
FORCEPROP 2 LAST BOM_COST MEM_VRD_VTT_DEF
J 0
(-700 2100);
DISPLAY 1.021277 (-700 2100);
PAINT ORANGE (-700 2100);
DISPLAY INVISIBLE (-700 2100);
FORCEPROP 2 LAST SEC 1
J 0
(-694 2115);
DISPLAY 0.680851 (-694 2115);
PAINT MONO (-694 2115);
DISPLAY INVISIBLE (-694 2115);
FORCEPROP 2 LAST ROOM VTT_DEF_PWR_VR
J 0
(-700 2050);
DISPLAY 1.021277 (-700 2050);
PAINT ORANGE (-700 2050);
DISPLAY INVISIBLE (-700 2050);
FORCEADD GND..1
(-325 1650);
FORCEPROP 3 LASTPIN (-325 1700) SIG_NAME GND\g
J 0
(-315 1710);
DISPLAY 0.659574 (-315 1710);
PAINT MONO (-315 1710);
DISPLAY INVISIBLE (-315 1710);
FORCEPROP 1 LAST PATH I16
J 0
(-250 1650);
DISPLAY 0.872340 (-250 1650);
PAINT AQUA (-250 1650);
DISPLAY INVISIBLE (-250 1650);
FORCEPROP 2 LAST ROOM VTT_DEF_PWR_VR
J 0
(-830 1730);
DISPLAY 1.021277 (-830 1730);
PAINT ORANGE (-830 1730);
DISPLAY INVISIBLE (-830 1730);
FORCEPROP 2 LAST BOM_COST MEM_VRD_VTT_DEF
J 0
(-830 1780);
DISPLAY 1.021277 (-830 1780);
PAINT ORANGE (-830 1780);
DISPLAY INVISIBLE (-830 1780);
FORCEPROP 1 LAST VOLTAGE 0.0V
J 0
(-370 1607);
DISPLAY 0.340426 (-370 1607);
PAINT SKYBLUE (-370 1607);
DISPLAY INVISIBLE (-370 1607);
FORCEPROP 2 LAST CDS_LIB mstr_symbols
J 0
(-325 1650);
PAINT MONO (-325 1650);
DISPLAY INVISIBLE (-325 1650);
FORCEPROP 1 LAST SIZE 1B
J 0
(-250 1600);
DISPLAY 0.893617 (-250 1600);
PAINT GREEN (-250 1600);
DISPLAY INVISIBLE (-250 1600);
FORCEPROP 1 LAST BODY_TYPE PLUMBING
J 0
(-370 1607);
DISPLAY 0.340426 (-370 1607);
PAINT GREEN (-370 1607);
DISPLAY INVISIBLE (-370 1607);
FORCEPROP 1 LAST HDL_POWER GND
J 0
(-325 1800);
DISPLAY 0.893617 (-325 1800);
PAINT GREEN (-325 1800);
DISPLAY INVISIBLE (-325 1800);
FORCEADD CAP..1
(-325 1925);
FORCEPROP 1 LAST VOLTAGE 4V
J 0
(-275 1925);
DISPLAY 0.617021 (-275 1925);
PAINT SKYBLUE (-275 1925);
FORCEPROP 1 LAST TOLERANCE 20%
J 0
(-275 1875);
DISPLAY 0.617021 (-275 1875);
PAINT SKYBLUE (-275 1875);
FORCEPROP 1 LAST MATERIAL X6S
J 0
(-275 1825);
DISPLAY 0.617021 (-275 1825);
PAINT SKYBLUE (-275 1825);
FORCEPROP 1 LASTPIN (-325 1825) $PN 2
J 0
(-315 1805);
DISPLAY 0.617021 (-315 1805);
PAINT WHITE (-315 1805);
FORCEPROP 1 LAST VALUE 10UF
J 0
(-275 1975);
DISPLAY 0.617021 (-275 1975);
PAINT SKYBLUE (-275 1975);
FORCEPROP 1 LAST PART_NUMBER E15431-001
J 0
(-275 1775);
DISPLAY 0.617021 (-275 1775);
PAINT BLUE (-275 1775);
FORCEPROP 1 LAST PACK_TYPE 0603LF
J 0
(-275 1725);
DISPLAY 0.617021 (-275 1725);
PAINT SKYBLUE (-275 1725);
FORCEPROP 1 LASTPIN (-325 2025) $PN 1
J 0
(-315 2005);
DISPLAY 0.617021 (-315 2005);
PAINT WHITE (-315 2005);
FORCEPROP 1 LAST LOCATION C6L3
J 0
(-275 2025);
DISPLAY 0.617021 (-275 2025);
PAINT AQUA (-275 2025);
FORCEPROP 1 LAST PATH I17
J 0
(-275 2075);
DISPLAY 0.978723 (-275 2075);
PAINT WHITE (-275 2075);
DISPLAY INVISIBLE (-275 2075);
FORCEPROP 0 LAST CDS_SEC 1
J 0
(-275 2075);
PAINT MONO (-275 2075);
DISPLAY INVISIBLE (-275 2075);
FORCEPROP 2 LAST CDS_LIB mstr_discrete
J 0
(-325 1925);
PAINT ORANGE (-325 1925);
DISPLAY INVISIBLE (-325 1925);
FORCEPROP 2 LAST ROOM VTT_DEF_PWR_VR
J 0
(-275 2075);
DISPLAY 1.021277 (-275 2075);
PAINT ORANGE (-275 2075);
DISPLAY INVISIBLE (-275 2075);
FORCEPROP 2 LAST CDS_LOCATION C6L3
J 0
(-275 2025);
DISPLAY 0.617021 (-275 2025);
PAINT AQUA (-275 2025);
DISPLAY INVISIBLE (-275 2025);
FORCEPROP 2 LAST SEC 1
J 0
(-269 2140);
DISPLAY 0.680851 (-269 2140);
PAINT MONO (-269 2140);
DISPLAY INVISIBLE (-269 2140);
FORCEPROP 2 LAST BOM_COST MEM_VRD_VTT_DEF
J 0
(-275 2125);
DISPLAY 1.021277 (-275 2125);
PAINT ORANGE (-275 2125);
DISPLAY INVISIBLE (-275 2125);
FORCEPROP 2 LAST SEC_TYPE 0603LF
J 0
(-269 2140);
DISPLAY 1.021277 (-269 2140);
PAINT ORANGE (-269 2140);
DISPLAY INVISIBLE (-269 2140);
FORCEADD GND..1
(1225 125);
FORCEPROP 3 LASTPIN (1225 175) SIG_NAME GND\g
J 0
(1235 185);
DISPLAY 0.659574 (1235 185);
PAINT MONO (1235 185);
DISPLAY INVISIBLE (1235 185);
FORCEPROP 1 LAST PATH I18
J 0
(1300 125);
DISPLAY 0.872340 (1300 125);
PAINT AQUA (1300 125);
DISPLAY INVISIBLE (1300 125);
FORCEPROP 2 LAST CDS_LIB mstr_symbols
J 0
(1225 125);
PAINT ORANGE (1225 125);
DISPLAY INVISIBLE (1225 125);
FORCEPROP 1 LAST SIZE 1B
J 0
(1300 75);
DISPLAY 0.872340 (1300 75);
PAINT AQUA (1300 75);
DISPLAY INVISIBLE (1300 75);
FORCEPROP 1 LAST VOLTAGE 0.0V
J 0
(1180 82);
DISPLAY 0.340426 (1180 82);
PAINT SKYBLUE (1180 82);
DISPLAY INVISIBLE (1180 82);
FORCEPROP 1 LAST BODY_TYPE PLUMBING
J 0
(1180 82);
DISPLAY 0.340426 (1180 82);
PAINT GREEN (1180 82);
DISPLAY INVISIBLE (1180 82);
FORCEPROP 1 LAST HDL_POWER GND
J 0
(1225 275);
DISPLAY 0.872340 (1225 275);
PAINT GREEN (1225 275);
DISPLAY INVISIBLE (1225 275);
FORCEADD GND..1
(1625 125);
FORCEPROP 3 LASTPIN (1625 175) SIG_NAME GND\g
J 0
(1635 185);
DISPLAY 0.659574 (1635 185);
PAINT MONO (1635 185);
DISPLAY INVISIBLE (1635 185);
FORCEPROP 1 LAST PATH I19
J 0
(1700 125);
DISPLAY 0.872340 (1700 125);
PAINT AQUA (1700 125);
DISPLAY INVISIBLE (1700 125);
FORCEPROP 1 LAST VOLTAGE 0.0V
J 0
(1580 82);
DISPLAY 0.340426 (1580 82);
PAINT SKYBLUE (1580 82);
DISPLAY INVISIBLE (1580 82);
FORCEPROP 2 LAST CDS_LIB mstr_symbols
J 0
(1625 125);
PAINT ORANGE (1625 125);
DISPLAY INVISIBLE (1625 125);
FORCEPROP 1 LAST SIZE 1B
J 0
(1700 75);
DISPLAY 0.872340 (1700 75);
PAINT AQUA (1700 75);
DISPLAY INVISIBLE (1700 75);
FORCEPROP 1 LAST BODY_TYPE PLUMBING
J 0
(1580 82);
DISPLAY 0.340426 (1580 82);
PAINT GREEN (1580 82);
DISPLAY INVISIBLE (1580 82);
FORCEPROP 1 LAST HDL_POWER GND
J 0
(1625 275);
DISPLAY 0.872340 (1625 275);
PAINT GREEN (1625 275);
DISPLAY INVISIBLE (1625 275);
FORCEADD CAP..1
R 2
(-1150 -850);
FORCEPROP 1 LAST PART_NUMBER A36096-046
J 2
(-1200 -1050);
DISPLAY 0.659574 (-1200 -1050);
PAINT BLUE (-1200 -1050);
FORCEPROP 1 LAST PACK_TYPE 0402LF
J 2
(-1200 -943);
DISPLAY 0.617021 (-1200 -943);
PAINT SKYBLUE (-1200 -943);
FORCEPROP 1 LAST TOLERANCE 10%
J 2
(-1200 -900);
DISPLAY 0.617021 (-1200 -900);
PAINT SKYBLUE (-1200 -900);
FORCEPROP 1 LAST VALUE 1000PF
J 2
(-1200 -800);
DISPLAY 0.617021 (-1200 -800);
PAINT SKYBLUE (-1200 -800);
FORCEPROP 1 LAST MATERIAL EMPTY
J 2
(-1191 -994);
DISPLAY 0.617021 (-1191 -994);
PAINT RED (-1191 -994);
FORCEPROP 1 LAST VOLTAGE 50V
J 2
(-1200 -850);
DISPLAY 0.617021 (-1200 -850);
PAINT SKYBLUE (-1200 -850);
FORCEPROP 1 LAST LOCATION C4A2
J 2
(-1200 -750);
DISPLAY 0.617021 (-1200 -750);
PAINT AQUA (-1200 -750);
FORCEPROP 1 LASTPIN (-1150 -950) $PN 2
J 2
(-1160 -970);
DISPLAY 0.617021 (-1160 -970);
PAINT WHITE (-1160 -970);
FORCEPROP 1 LASTPIN (-1150 -750) $PN 1
J 2
(-1160 -770);
DISPLAY 0.617021 (-1160 -770);
PAINT WHITE (-1160 -770);
FORCEPROP 1 LAST PATH I2
J 2
(-1200 -700);
DISPLAY 0.978723 (-1200 -700);
PAINT WHITE (-1200 -700);
DISPLAY INVISIBLE (-1200 -700);
FORCEPROP 0 LAST CDS_SEC 1
J 0
(-1200 -700);
PAINT MONO (-1200 -700);
DISPLAY INVISIBLE (-1200 -700);
FORCEPROP 2 LAST BOM_COST MEM_VRD_VTT_DEF
J 0
(-1185 -645);
DISPLAY 1.021277 (-1185 -645);
PAINT ORANGE (-1185 -645);
DISPLAY INVISIBLE (-1185 -645);
FORCEPROP 2 LAST CDS_LOCATION C4A2
J 2
(-1200 -750);
DISPLAY 0.617021 (-1200 -750);
PAINT AQUA (-1200 -750);
DISPLAY INVISIBLE (-1200 -750);
FORCEPROP 2 LAST ROOM VTT_DEF_PWR_VR
J 0
(-1185 -695);
DISPLAY 1.021277 (-1185 -695);
PAINT ORANGE (-1185 -695);
DISPLAY INVISIBLE (-1185 -695);
FORCEPROP 2 LAST CDS_LIB mstr_discrete
J 0
(-1150 -850);
PAINT ORANGE (-1150 -850);
DISPLAY INVISIBLE (-1150 -850);
FORCEPROP 2 LAST SEC_TYPE 0402LF
J 0
(-1179 -630);
DISPLAY 1.021277 (-1179 -630);
PAINT ORANGE (-1179 -630);
DISPLAY INVISIBLE (-1179 -630);
FORCEPROP 2 LAST SEC 1
J 0
(-1179 -630);
DISPLAY 0.680851 (-1179 -630);
PAINT MONO (-1179 -630);
DISPLAY INVISIBLE (-1179 -630);
FORCEADD CAP..1
(1625 400);
FORCEPROP 1 LAST LOCATION C4A9
J 0
(1675 500);
DISPLAY 0.617021 (1675 500);
PAINT AQUA (1675 500);
FORCEPROP 1 LAST PART_NUMBER D97712-011
J 0
(1675 350);
DISPLAY 0.617021 (1675 350);
PAINT BLUE (1675 350);
FORCEPROP 1 LAST MATERIAL X6S
J 0
(1800 400);
DISPLAY 0.617021 (1800 400);
PAINT SKYBLUE (1800 400);
FORCEPROP 1 LAST VALUE 1.0UF
J 0
(1675 450);
DISPLAY 0.617021 (1675 450);
PAINT SKYBLUE (1675 450);
FORCEPROP 1 LAST VOLTAGE 16V
J 0
(1825 450);
DISPLAY 0.617021 (1825 450);
PAINT SKYBLUE (1825 450);
FORCEPROP 1 LAST TOLERANCE 10%
J 0
(1675 400);
DISPLAY 0.617021 (1675 400);
PAINT SKYBLUE (1675 400);
FORCEPROP 1 LASTPIN (1625 300) $PN 2
J 0
(1635 280);
DISPLAY 0.617021 (1635 280);
PAINT WHITE (1635 280);
FORCEPROP 1 LAST PACK_TYPE 0402
J 0
(1675 300);
DISPLAY 0.617021 (1675 300);
PAINT SKYBLUE (1675 300);
FORCEPROP 1 LASTPIN (1625 500) $PN 1
J 0
(1635 480);
DISPLAY 0.617021 (1635 480);
PAINT WHITE (1635 480);
FORCEPROP 1 LAST PATH I20
J 0
(1675 550);
DISPLAY 0.978723 (1675 550);
PAINT WHITE (1675 550);
DISPLAY INVISIBLE (1675 550);
FORCEPROP 0 LAST CDS_SEC 1
J 0
(1675 550);
PAINT MONO (1675 550);
DISPLAY INVISIBLE (1675 550);
FORCEPROP 2 LAST CDS_LIB mstr_discrete
J 0
(1625 400);
PAINT ORANGE (1625 400);
DISPLAY INVISIBLE (1625 400);
FORCEPROP 2 LAST SEC 1
J 0
(1681 615);
DISPLAY 0.680851 (1681 615);
PAINT MONO (1681 615);
DISPLAY INVISIBLE (1681 615);
FORCEPROP 2 LAST BOM_COST MEM_VRD_VTT_DEF
J 0
(1675 600);
DISPLAY 1.021277 (1675 600);
PAINT ORANGE (1675 600);
DISPLAY INVISIBLE (1675 600);
FORCEPROP 2 LAST SEC_TYPE 0402
J 0
(1681 615);
DISPLAY 1.021277 (1681 615);
PAINT ORANGE (1681 615);
DISPLAY INVISIBLE (1681 615);
FORCEPROP 2 LAST ROOM VTT_DEF_PWR_VR
J 0
(1675 550);
DISPLAY 1.021277 (1675 550);
PAINT ORANGE (1675 550);
DISPLAY INVISIBLE (1675 550);
FORCEPROP 2 LAST CDS_LOCATION C4A9
J 0
(1675 500);
DISPLAY 0.617021 (1675 500);
PAINT AQUA (1675 500);
DISPLAY INVISIBLE (1675 500);
FORCEADD GND..1
(3075 925);
FORCEPROP 3 LASTPIN (3075 975) SIG_NAME GND\g
J 0
(3085 985);
DISPLAY 0.659574 (3085 985);
PAINT MONO (3085 985);
DISPLAY INVISIBLE (3085 985);
FORCEPROP 1 LAST PATH I21
J 0
(3150 925);
DISPLAY 0.872340 (3150 925);
PAINT AQUA (3150 925);
DISPLAY INVISIBLE (3150 925);
FORCEPROP 1 LAST VOLTAGE 0.0V
J 0
(3030 882);
DISPLAY 0.340426 (3030 882);
PAINT SKYBLUE (3030 882);
DISPLAY INVISIBLE (3030 882);
FORCEPROP 1 LAST SIZE 1B
J 0
(3150 875);
DISPLAY 0.893617 (3150 875);
PAINT GREEN (3150 875);
DISPLAY INVISIBLE (3150 875);
FORCEPROP 2 LAST CDS_LIB mstr_symbols
J 0
(3075 925);
DISPLAY 0.744681 (3075 925);
PAINT MONO (3075 925);
DISPLAY INVISIBLE (3075 925);
FORCEPROP 1 LAST BODY_TYPE PLUMBING
J 0
(3030 882);
DISPLAY 0.340426 (3030 882);
PAINT GREEN (3030 882);
DISPLAY INVISIBLE (3030 882);
FORCEPROP 1 LAST HDL_POWER GND
J 0
(3075 1075);
DISPLAY 0.893617 (3075 1075);
PAINT GREEN (3075 1075);
DISPLAY INVISIBLE (3075 1075);
FORCEADD CAP..1
(3075 1175);
FORCEPROP 1 LAST PACK_TYPE 0402LF
J 0
(3125 975);
DISPLAY 0.617021 (3125 975);
PAINT SKYBLUE (3125 975);
FORCEPROP 1 LAST PART_NUMBER A36096-046
J 0
(3125 1025);
DISPLAY 0.617021 (3125 1025);
PAINT BLUE (3125 1025);
FORCEPROP 1 LAST LOCATION C4A12
J 0
(3125 1275);
DISPLAY 0.617021 (3125 1275);
PAINT AQUA (3125 1275);
FORCEPROP 1 LAST MATERIAL X7R
J 0
(3125 1075);
DISPLAY 0.617021 (3125 1075);
PAINT SKYBLUE (3125 1075);
FORCEPROP 1 LAST TOLERANCE 10%
J 0
(3125 1125);
DISPLAY 0.617021 (3125 1125);
PAINT SKYBLUE (3125 1125);
FORCEPROP 1 LAST VOLTAGE 50V
J 0
(3125 1175);
DISPLAY 0.617021 (3125 1175);
PAINT SKYBLUE (3125 1175);
FORCEPROP 1 LASTPIN (3075 1075) $PN 2
J 0
(3085 1055);
DISPLAY 0.617021 (3085 1055);
PAINT WHITE (3085 1055);
FORCEPROP 1 LASTPIN (3075 1275) $PN 1
J 0
(3085 1255);
DISPLAY 0.617021 (3085 1255);
PAINT WHITE (3085 1255);
FORCEPROP 1 LAST VALUE 1000PF
J 0
(3125 1225);
DISPLAY 0.617021 (3125 1225);
PAINT SKYBLUE (3125 1225);
FORCEPROP 1 LAST PATH I22
J 0
(3125 1325);
DISPLAY 0.978723 (3125 1325);
PAINT WHITE (3125 1325);
DISPLAY INVISIBLE (3125 1325);
FORCEPROP 0 LAST CDS_SEC 1
J 0
(3125 1325);
PAINT MONO (3125 1325);
DISPLAY INVISIBLE (3125 1325);
FORCEPROP 2 LAST CDS_LIB mstr_discrete
J 0
(3075 1175);
DISPLAY 0.744681 (3075 1175);
PAINT MONO (3075 1175);
DISPLAY INVISIBLE (3075 1175);
FORCEPROP 2 LAST CDS_LOCATION C4A12
J 0
(3125 1275);
DISPLAY 0.617021 (3125 1275);
PAINT AQUA (3125 1275);
DISPLAY INVISIBLE (3125 1275);
FORCEPROP 2 LAST ROOM VTT_DEF_PWR_VR
J 0
(3125 1325);
DISPLAY 1.021277 (3125 1325);
PAINT ORANGE (3125 1325);
DISPLAY INVISIBLE (3125 1325);
FORCEPROP 2 LAST SEC_TYPE 0402LF
J 0
(3125 1375);
DISPLAY 1.021277 (3125 1375);
PAINT ORANGE (3125 1375);
DISPLAY INVISIBLE (3125 1375);
FORCEPROP 2 LAST SEC 1
J 0
(3125 1375);
DISPLAY 0.680851 (3125 1375);
PAINT MONO (3125 1375);
DISPLAY INVISIBLE (3125 1375);
FORCEPROP 2 LAST BOM_COST MEM_VRD_VTT_DEF
J 0
(3125 1375);
DISPLAY 1.021277 (3125 1375);
PAINT ORANGE (3125 1375);
DISPLAY INVISIBLE (3125 1375);
FORCEADD RES..2
(2500 1650);
FORCEPROP 1 LAST PACK_TYPE 0402
J 0
(2540 1475);
DISPLAY 0.617021 (2540 1475);
PAINT SKYBLUE (2540 1475);
FORCEPROP 1 LAST PART_NUMBER G21796-016
J 0
(2540 1525);
DISPLAY 0.617021 (2540 1525);
PAINT BLUE (2540 1525);
FORCEPROP 1 LAST MATERIAL CHIP
J 0
(2540 1575);
DISPLAY 0.617021 (2540 1575);
PAINT SKYBLUE (2540 1575);
FORCEPROP 1 LAST WATTAGE 1/16W
J 0
(2540 1625);
DISPLAY 0.617021 (2540 1625);
PAINT SKYBLUE (2540 1625);
FORCEPROP 1 LAST LOCATION R6L9
J 0
(2545 1775);
DISPLAY 0.617021 (2545 1775);
PAINT AQUA (2545 1775);
FORCEPROP 1 LASTPIN (2500 1550) $PN 2
J 0
(2505 1560);
DISPLAY 0.617021 (2505 1560);
PAINT WHITE (2505 1560);
FORCEPROP 1 LASTPIN (2500 1750) $PN 1
J 0
(2505 1712);
DISPLAY 0.617021 (2505 1712);
PAINT WHITE (2505 1712);
FORCEPROP 1 LAST TOLERANCE 1%
J 0
(2545 1675);
DISPLAY 0.617021 (2545 1675);
PAINT SKYBLUE (2545 1675);
FORCEPROP 1 LAST VALUE 10.0K
J 0
(2545 1725);
DISPLAY 0.617021 (2545 1725);
PAINT SKYBLUE (2545 1725);
FORCEPROP 1 LAST PATH I23
J 0
(2550 1825);
DISPLAY 0.978723 (2550 1825);
PAINT WHITE (2550 1825);
DISPLAY INVISIBLE (2550 1825);
FORCEPROP 0 LAST CDS_SEC 1
J 0
(2550 1825);
PAINT MONO (2550 1825);
DISPLAY INVISIBLE (2550 1825);
FORCEPROP 2 LAST ROOM VTT_DEF_PWR_VR
J 0
(2550 1825);
DISPLAY 1.021277 (2550 1825);
PAINT ORANGE (2550 1825);
DISPLAY INVISIBLE (2550 1825);
FORCEPROP 2 LAST CDS_LOCATION R6L9
J 0
(2545 1775);
DISPLAY 0.617021 (2545 1775);
PAINT AQUA (2545 1775);
DISPLAY INVISIBLE (2545 1775);
FORCEPROP 2 LAST SEC 1
J 0
(2550 1871);
DISPLAY 0.680851 (2550 1871);
PAINT MONO (2550 1871);
DISPLAY INVISIBLE (2550 1871);
FORCEPROP 2 LAST SEC_TYPE 0402
J 0
(2550 1871);
DISPLAY 1.021277 (2550 1871);
PAINT ORANGE (2550 1871);
DISPLAY INVISIBLE (2550 1871);
FORCEPROP 2 LAST BOM_COST MEM_VRD_VTT_DEF
J 0
(2550 1875);
DISPLAY 1.021277 (2550 1875);
PAINT ORANGE (2550 1875);
DISPLAY INVISIBLE (2550 1875);
FORCEPROP 2 LAST CDS_LIB mstr_discrete
J 0
(2500 1650);
PAINT ORANGE (2500 1650);
DISPLAY INVISIBLE (2500 1650);
FORCEADD P3V3..1
(2500 1875);
FORCEPROP 3 LASTPIN (2500 1825) SIG_NAME P3V3\g
J 0
(2510 1835);
DISPLAY 0.659574 (2510 1835);
PAINT MONO (2510 1835);
DISPLAY INVISIBLE (2510 1835);
FORCEPROP 1 LAST PATH I24
J 0
(2545 1877);
DISPLAY 0.340426 (2545 1877);
PAINT GREEN (2545 1877);
DISPLAY INVISIBLE (2545 1877);
FORCEPROP 1 LAST SIZE 1B
J 0
(2545 1897);
DISPLAY 0.340426 (2545 1897);
PAINT GREEN (2545 1897);
DISPLAY INVISIBLE (2545 1897);
FORCEPROP 1 LAST VOLTAGE 3.3V
J 0
(2455 1832);
DISPLAY 0.340426 (2455 1832);
PAINT SKYBLUE (2455 1832);
DISPLAY INVISIBLE (2455 1832);
FORCEPROP 2 LAST CDS_LIB mstr_symbols
J 0
(2500 1875);
PAINT ORANGE (2500 1875);
DISPLAY INVISIBLE (2500 1875);
FORCEPROP 1 LAST BODY_TYPE PLUMBING
J 0
(2455 1832);
DISPLAY 0.340426 (2455 1832);
PAINT GREEN (2455 1832);
DISPLAY INVISIBLE (2455 1832);
FORCEPROP 1 LAST HDL_POWER P3V3
J 0
(2175 1750);
DISPLAY 0.872340 (2175 1750);
PAINT ORANGE (2175 1750);
DISPLAY INVISIBLE (2175 1750);
FORCEADD PVTT_DEF..1
(2750 3200);
FORCEPROP 3 LASTPIN (2750 3150) SIG_NAME PVTT_DEF\g
J 0
(2760 3160);
DISPLAY 0.659574 (2760 3160);
PAINT MONO (2760 3160);
DISPLAY INVISIBLE (2760 3160);
FORCEPROP 1 LAST PATH I25
J 0
(2800 3225);
DISPLAY 0.872340 (2800 3225);
PAINT AQUA (2800 3225);
DISPLAY INVISIBLE (2800 3225);
FORCEPROP 1 LAST VOLTAGE 0.6V
J 0
(2705 3157);
DISPLAY 0.340426 (2705 3157);
PAINT SKYBLUE (2705 3157);
DISPLAY INVISIBLE (2705 3157);
FORCEPROP 2 LAST CDS_LIB mstr_symbols
J 0
(2750 3200);
PAINT ORANGE (2750 3200);
DISPLAY INVISIBLE (2750 3200);
FORCEPROP 2 LAST BOM_COST MEM_VRD_PVDDQ_AB
J 0
(2825 3300);
PAINT MONO (2825 3300);
DISPLAY INVISIBLE (2825 3300);
FORCEPROP 2 LAST ROOM VTT_DEF_PWR_VR
J 0
(3000 3300);
PAINT ORANGE (3000 3300);
DISPLAY INVISIBLE (3000 3300);
FORCEPROP 1 LAST BODY_TYPE PLUMBING
J 0
(2705 3157);
DISPLAY 0.340426 (2705 3157);
PAINT GREEN (2705 3157);
DISPLAY INVISIBLE (2705 3157);
FORCEPROP 1 LAST HDL_POWER PVTT_DEF
J 1
(2750 3250);
DISPLAY 0.872340 (2750 3250);
PAINT GREEN (2750 3250);
DISPLAY INVISIBLE (2750 3250);
FORCEADD CAP..1
(3200 575);
FORCEPROP 0 LAST GROUP PWR_MLCC_CAP
J 0
(3256 362);
DISPLAY 0.638298 (3256 362);
PAINT BROWN (3256 362);
DISPLAY BOTH (3256 362);
FORCEPROP 1 LAST VALUE 22UF
J 0
(3250 625);
DISPLAY 0.617021 (3250 625);
PAINT SKYBLUE (3250 625);
FORCEPROP 1 LAST PART_NUMBER C95333-002
R 1
J 0
(3150 425);
DISPLAY 0.617021 (3150 425);
PAINT BLUE (3150 425);
FORCEPROP 1 LAST TOLERANCE 20%
J 0
(3250 525);
DISPLAY 0.617021 (3250 525);
PAINT SKYBLUE (3250 525);
FORCEPROP 1 LAST MATERIAL X6S
J 0
(3250 475);
DISPLAY 0.617021 (3250 475);
PAINT SKYBLUE (3250 475);
FORCEPROP 1 LAST VOLTAGE 4V
J 0
(3250 575);
DISPLAY 0.617021 (3250 575);
PAINT SKYBLUE (3250 575);
FORCEPROP 1 LAST LOCATION C4A1
J 0
(3250 675);
DISPLAY 0.617021 (3250 675);
PAINT AQUA (3250 675);
FORCEPROP 1 LASTPIN (3200 675) $PN 1
J 0
(3210 655);
DISPLAY 0.617021 (3210 655);
PAINT WHITE (3210 655);
FORCEPROP 1 LASTPIN (3200 475) $PN 2
J 0
(3210 455);
DISPLAY 0.617021 (3210 455);
PAINT WHITE (3210 455);
FORCEPROP 1 LAST PACK_TYPE 0805LF
J 0
(3250 425);
DISPLAY 0.617021 (3250 425);
PAINT SKYBLUE (3250 425);
FORCEPROP 1 LAST PATH I28
J 0
(3250 725);
DISPLAY 0.978723 (3250 725);
PAINT WHITE (3250 725);
DISPLAY INVISIBLE (3250 725);
FORCEPROP 0 LAST CDS_SEC 1
J 0
(3250 725);
PAINT MONO (3250 725);
DISPLAY INVISIBLE (3250 725);
FORCEPROP 2 LAST CDS_LIB mstr_discrete
J 0
(3200 575);
PAINT ORANGE (3200 575);
DISPLAY INVISIBLE (3200 575);
FORCEPROP 2 LAST CDS_LOCATION C4A1
J 0
(3250 675);
DISPLAY 0.617021 (3250 675);
PAINT AQUA (3250 675);
DISPLAY INVISIBLE (3250 675);
FORCEPROP 2 LAST ROOM VTT_DEF_PWR_VR
J 0
(3270 730);
DISPLAY 1.021277 (3270 730);
PAINT ORANGE (3270 730);
DISPLAY INVISIBLE (3270 730);
FORCEPROP 2 LAST SEC_TYPE 0805LF
J 0
(3251 795);
DISPLAY 1.021277 (3251 795);
PAINT ORANGE (3251 795);
DISPLAY INVISIBLE (3251 795);
FORCEPROP 2 LAST BOM_COST MEM_VRD_VTT_DEF
J 0
(3270 780);
DISPLAY 1.021277 (3270 780);
PAINT ORANGE (3270 780);
DISPLAY INVISIBLE (3270 780);
FORCEPROP 2 LAST SEC 1
J 0
(3251 795);
DISPLAY 0.680851 (3251 795);
PAINT MONO (3251 795);
DISPLAY INVISIBLE (3251 795);
FORCEADD GND..1
(3200 175);
FORCEPROP 3 LASTPIN (3200 225) SIG_NAME GND\g
J 0
(3210 235);
DISPLAY 0.659574 (3210 235);
PAINT MONO (3210 235);
DISPLAY INVISIBLE (3210 235);
FORCEPROP 1 LAST PATH I29
J 0
(3275 175);
DISPLAY 0.872340 (3275 175);
PAINT AQUA (3275 175);
DISPLAY INVISIBLE (3275 175);
FORCEPROP 1 LAST VOLTAGE 0.0V
J 0
(3155 132);
DISPLAY 0.340426 (3155 132);
PAINT SKYBLUE (3155 132);
DISPLAY INVISIBLE (3155 132);
FORCEPROP 1 LAST SIZE 1B
J 0
(3275 125);
DISPLAY 0.893617 (3275 125);
PAINT GREEN (3275 125);
DISPLAY INVISIBLE (3275 125);
FORCEPROP 2 LAST CDS_LIB mstr_symbols
J 0
(3200 175);
PAINT ORANGE (3200 175);
DISPLAY INVISIBLE (3200 175);
FORCEPROP 1 LAST BODY_TYPE PLUMBING
J 0
(3155 132);
DISPLAY 0.340426 (3155 132);
PAINT GREEN (3155 132);
DISPLAY INVISIBLE (3155 132);
FORCEPROP 1 LAST HDL_POWER GND
J 0
(3200 325);
DISPLAY 0.893617 (3200 325);
PAINT GREEN (3200 325);
DISPLAY INVISIBLE (3200 325);
FORCEADD OFFPAGE..1
(-2200 -325);
FORCEPROP 2 LAST $XR0 218 
J 0
(-2452 -325);
DISPLAY 0.638298 (-2452 -325);
PAINT MONO (-2452 -325);
FORCEPROP 2 LAST PATH I3
J 0
(-2450 -275);
DISPLAY 1.021277 (-2450 -275);
PAINT ORANGE (-2450 -275);
DISPLAY INVISIBLE (-2450 -275);
FORCEPROP 2 LAST CDS_LIB mstr_standard
J 0
(-2200 -325);
DISPLAY 0.744681 (-2200 -325);
PAINT MONO (-2200 -325);
DISPLAY INVISIBLE (-2200 -325);
FORCEPROP 1 LAST OFFPAGE TRUE
J 0
(-1875 -450);
DISPLAY 0.872340 (-1875 -450);
PAINT GREEN (-1875 -450);
DISPLAY INVISIBLE (-1875 -450);
FORCEPROP 1 LAST COMMENT_BODY TRUE
J 0
(-2075 -425);
DISPLAY 0.872340 (-2075 -425);
PAINT GREEN (-2075 -425);
DISPLAY INVISIBLE (-2075 -425);
FORCEADD SHUNT..1
(4175 -425);
FORCEPROP 1 LAST PART_NUMBER N_A
J 0
(4100 -515);
DISPLAY 0.617021 (4100 -515);
PAINT BLUE (4100 -515);
FORCEPROP 1 LASTPIN (4025 -425) $PN 1
J 2
(4075 -415);
DISPLAY 0.617021 (4075 -415);
PAINT ORANGE (4075 -415);
FORCEPROP 1 LASTPIN (4325 -425) $PN 2
J 0
(4285 -415);
DISPLAY 0.617021 (4285 -415);
PAINT ORANGE (4285 -415);
FORCEPROP 1 LAST LOCATION SH5L1
J 0
(4100 -375);
DISPLAY 0.617021 (4100 -375);
PAINT AQUA (4100 -375);
FORCEPROP 1 LAST PATH I30
J 0
(4125 -325);
DISPLAY 0.978723 (4125 -325);
PAINT ORANGE (4125 -325);
DISPLAY INVISIBLE (4125 -325);
FORCEPROP 0 LAST CDS_SEC 1
J 0
(4100 -325);
PAINT MONO (4100 -325);
DISPLAY INVISIBLE (4100 -325);
FORCEPROP 0 LAST CDS_LOCATION SH5L1
J 0
(4100 -325);
PAINT MONO (4100 -325);
DISPLAY INVISIBLE (4100 -325);
FORCEPROP 1 LAST PACK_TYPE SH0201
J 0
(4115 -610);
DISPLAY 0.978723 (4115 -610);
PAINT SKYBLUE (4115 -610);
DISPLAY INVISIBLE (4115 -610);
FORCEPROP 1 LAST PIN_SHORT A:B
J 0
(4100 -675);
DISPLAY 1.021277 (4100 -675);
PAINT ORANGE (4100 -675);
DISPLAY INVISIBLE (4100 -675);
FORCEPROP 1 LAST MATERIAL EMPTY
J 0
(4100 -560);
DISPLAY 0.978723 (4100 -560);
PAINT RED (4100 -560);
DISPLAY INVISIBLE (4100 -560);
FORCEPROP 2 LAST CDS_LIB mstr_misc
J 0
(4175 -425);
PAINT ORANGE (4175 -425);
DISPLAY INVISIBLE (4175 -425);
FORCEPROP 0 LAST SEC 1
J 0
(4100 -325);
DISPLAY 0.680851 (4100 -325);
PAINT MONO (4100 -325);
DISPLAY INVISIBLE (4100 -325);
FORCEPROP 2 LAST SEC_TYPE SH0201
J 0
(4125 -275);
DISPLAY 1.021277 (4125 -275);
PAINT ORANGE (4125 -275);
DISPLAY INVISIBLE (4125 -275);
FORCEADD RES..1
(3475 1375);
FORCEPROP 1 LAST PART_NUMBER G21796-074
J 0
(3425 1475);
DISPLAY 0.617021 (3425 1475);
PAINT BLUE (3425 1475);
FORCEPROP 1 LASTPIN (3575 1375) $PN 2
J 0
(3537 1387);
DISPLAY 0.617021 (3537 1387);
PAINT ORANGE (3537 1387);
FORCEPROP 1 LASTPIN (3375 1375) $PN 1
J 0
(3387 1387);
DISPLAY 0.617021 (3387 1387);
PAINT ORANGE (3387 1387);
FORCEPROP 1 LAST PACK_TYPE 0402
J 0
(3725 1225);
DISPLAY 0.617021 (3725 1225);
PAINT SKYBLUE (3725 1225);
FORCEPROP 1 LAST TOLERANCE 1%
J 0
(3475 1275);
DISPLAY 0.617021 (3475 1275);
PAINT SKYBLUE (3475 1275);
FORCEPROP 1 LAST LOCATION R4A6
J 0
(3425 1425);
DISPLAY 0.617021 (3425 1425);
PAINT AQUA (3425 1425);
FORCEPROP 1 LAST MATERIAL CHIP
J 0
(3475 1225);
DISPLAY 0.617021 (3475 1225);
PAINT SKYBLUE (3475 1225);
FORCEPROP 1 LAST WATTAGE 1/16W
J 2
(3450 1225);
DISPLAY 0.617021 (3450 1225);
PAINT SKYBLUE (3450 1225);
FORCEPROP 1 LAST VALUE 33.2
J 2
(3450 1275);
DISPLAY 0.617021 (3450 1275);
PAINT SKYBLUE (3450 1275);
FORCEPROP 1 LAST PATH I31
J 0
(3425 1525);
DISPLAY 0.978723 (3425 1525);
PAINT WHITE (3425 1525);
DISPLAY INVISIBLE (3425 1525);
FORCEPROP 0 LAST CDS_SEC 1
J 0
(3425 1525);
PAINT MONO (3425 1525);
DISPLAY INVISIBLE (3425 1525);
FORCEPROP 2 LAST CDS_LOCATION R4A6
J 0
(3425 1425);
DISPLAY 0.617021 (3425 1425);
PAINT AQUA (3425 1425);
DISPLAY INVISIBLE (3425 1425);
FORCEPROP 2 LAST CDS_LIB mstr_discrete
J 0
(3475 1375);
PAINT MONO (3475 1375);
DISPLAY INVISIBLE (3475 1375);
FORCEPROP 2 LAST SEC_TYPE 0402
J 0
(3425 1575);
DISPLAY 1.021277 (3425 1575);
PAINT ORANGE (3425 1575);
DISPLAY INVISIBLE (3425 1575);
FORCEPROP 2 LAST SEC 1
J 0
(3425 1575);
DISPLAY 0.680851 (3425 1575);
PAINT MONO (3425 1575);
DISPLAY INVISIBLE (3425 1575);
FORCEADD OFFPAGE..2
(4600 1375);
FORCEPROP 2 LAST $XR0 221 
J 0
(4789 1375);
DISPLAY 0.638298 (4789 1375);
PAINT MONO (4789 1375);
FORCEPROP 2 LAST $XR1 191 
J 0
(4909 1375);
DISPLAY 0.638298 (4909 1375);
PAINT MONO (4909 1375);
FORCEPROP 2 LAST PATH I33
J 0
(4925 1425);
DISPLAY 1.021277 (4925 1425);
PAINT ORANGE (4925 1425);
DISPLAY INVISIBLE (4925 1425);
FORCEPROP 2 LAST CDS_LIB mstr_standard
J 0
(4600 1375);
DISPLAY 0.744681 (4600 1375);
PAINT MONO (4600 1375);
DISPLAY INVISIBLE (4600 1375);
FORCEPROP 1 LAST OFFPAGE TRUE
J 0
(4925 1250);
DISPLAY 0.872340 (4925 1250);
PAINT GREEN (4925 1250);
DISPLAY INVISIBLE (4925 1250);
FORCEPROP 1 LAST COMMENT_BODY TRUE
J 0
(4555 1280);
DISPLAY 0.872340 (4555 1280);
PAINT GREEN (4555 1280);
DISPLAY INVISIBLE (4555 1280);
FORCEADD PVTT_DEF..1
(4750 1125);
FORCEPROP 3 LASTPIN (4750 1075) SIG_NAME PVTT_DEF\g
J 0
(4760 1085);
DISPLAY 0.659574 (4760 1085);
PAINT MONO (4760 1085);
DISPLAY INVISIBLE (4760 1085);
FORCEPROP 1 LAST PATH I34
J 0
(4800 1150);
DISPLAY 0.872340 (4800 1150);
PAINT AQUA (4800 1150);
DISPLAY INVISIBLE (4800 1150);
FORCEPROP 1 LAST VOLTAGE 0.6V
J 0
(4705 1082);
DISPLAY 0.340426 (4705 1082);
PAINT SKYBLUE (4705 1082);
DISPLAY INVISIBLE (4705 1082);
FORCEPROP 2 LAST CDS_LIB mstr_symbols
J 0
(4750 1125);
PAINT ORANGE (4750 1125);
DISPLAY INVISIBLE (4750 1125);
FORCEPROP 1 LAST BODY_TYPE PLUMBING
J 0
(4705 1082);
DISPLAY 0.340426 (4705 1082);
PAINT GREEN (4705 1082);
DISPLAY INVISIBLE (4705 1082);
FORCEPROP 1 LAST HDL_POWER PVTT_DEF
J 1
(4750 1175);
DISPLAY 0.872340 (4750 1175);
PAINT GREEN (4750 1175);
DISPLAY INVISIBLE (4750 1175);
FORCEADD GND..1
(2750 2275);
FORCEPROP 3 LASTPIN (2750 2325) SIG_NAME GND\g
J 0
(2760 2335);
DISPLAY 0.659574 (2760 2335);
PAINT MONO (2760 2335);
DISPLAY INVISIBLE (2760 2335);
FORCEPROP 1 LAST HDL_POWER GND
J 0
(2750 2425);
DISPLAY 0.893617 (2750 2425);
PAINT GREEN (2750 2425);
DISPLAY INVISIBLE (2750 2425);
FORCEPROP 1 LAST BODY_TYPE PLUMBING
J 0
(2705 2232);
DISPLAY 0.340426 (2705 2232);
PAINT GREEN (2705 2232);
DISPLAY INVISIBLE (2705 2232);
FORCEPROP 2 LAST CDS_LIB mstr_symbols
J 0
(2750 2275);
PAINT ORANGE (2750 2275);
DISPLAY INVISIBLE (2750 2275);
FORCEPROP 2 LAST BOM_COST MEM_VRD_PVDDQ_AB
J 0
(2425 2350);
PAINT MONO (2425 2350);
DISPLAY INVISIBLE (2425 2350);
FORCEPROP 1 LAST SIZE 1B
J 0
(2825 2225);
DISPLAY 0.893617 (2825 2225);
PAINT GREEN (2825 2225);
DISPLAY INVISIBLE (2825 2225);
FORCEPROP 1 LAST VOLTAGE 0.0V
J 0
(2705 2232);
DISPLAY 0.340426 (2705 2232);
PAINT SKYBLUE (2705 2232);
DISPLAY INVISIBLE (2705 2232);
FORCEPROP 2 LAST ROOM VTT_DEF_PWR_VR
J 0
(2200 2350);
PAINT ORANGE (2200 2350);
DISPLAY INVISIBLE (2200 2350);
FORCEPROP 1 LAST PATH I35
J 0
(2825 2275);
DISPLAY 0.872340 (2825 2275);
PAINT AQUA (2825 2275);
DISPLAY INVISIBLE (2825 2275);
FORCEADD PVDDQ_DEF..1
(-2225 2325);
FORCEPROP 3 LASTPIN (-2225 2275) SIG_NAME PVDDQ_DEF\g
J 0
(-2215 2285);
DISPLAY 0.659574 (-2215 2285);
PAINT MONO (-2215 2285);
DISPLAY INVISIBLE (-2215 2285);
FORCEPROP 1 LAST PATH I37
J 0
(-2175 2350);
DISPLAY 0.872340 (-2175 2350);
PAINT AQUA (-2175 2350);
DISPLAY INVISIBLE (-2175 2350);
FORCEPROP 1 LAST VOLTAGE 1.2V
J 0
(-2270 2282);
DISPLAY 0.340426 (-2270 2282);
PAINT SKYBLUE (-2270 2282);
DISPLAY INVISIBLE (-2270 2282);
FORCEPROP 2 LAST CDS_LIB mstr_symbols
J 0
(-2225 2325);
PAINT ORANGE (-2225 2325);
DISPLAY INVISIBLE (-2225 2325);
FORCEPROP 1 LAST BODY_TYPE PLUMBING
J 0
(-2270 2282);
DISPLAY 0.340426 (-2270 2282);
PAINT GREEN (-2270 2282);
DISPLAY INVISIBLE (-2270 2282);
FORCEPROP 1 LAST HDL_POWER PVDDQ_DEF
J 1
(-2225 2375);
DISPLAY 0.872340 (-2225 2375);
PAINT GREEN (-2225 2375);
DISPLAY INVISIBLE (-2225 2375);
FORCEADD RES..1
(-1300 -325);
FORCEPROP 1 LAST PACK_TYPE 0402
J 0
(-1375 -500);
DISPLAY 0.617021 (-1375 -500);
PAINT SKYBLUE (-1375 -500);
FORCEPROP 1 LAST MATERIAL CHIP
J 0
(-1600 -500);
DISPLAY 0.617021 (-1600 -500);
PAINT SKYBLUE (-1600 -500);
FORCEPROP 1 LAST WATTAGE 1/16W
J 2
(-1450 -425);
DISPLAY 0.617021 (-1450 -425);
PAINT SKYBLUE (-1450 -425);
FORCEPROP 1 LAST VALUE 0.0
J 2
(-1325 -425);
DISPLAY 0.617021 (-1325 -425);
PAINT SKYBLUE (-1325 -425);
FORCEPROP 1 LAST TOLERANCE 5%
J 0
(-1300 -425);
DISPLAY 0.617021 (-1300 -425);
PAINT SKYBLUE (-1300 -425);
FORCEPROP 1 LAST PART_NUMBER G21497-005
J 0
(-1457 -381);
DISPLAY 0.617021 (-1457 -381);
PAINT BLUE (-1457 -381);
FORCEPROP 1 LAST LOCATION R4A2
J 0
(-1350 -275);
DISPLAY 0.617021 (-1350 -275);
PAINT AQUA (-1350 -275);
FORCEPROP 1 LASTPIN (-1400 -325) $PN 1
J 0
(-1388 -313);
DISPLAY 0.617021 (-1388 -313);
PAINT WHITE (-1388 -313);
FORCEPROP 1 LASTPIN (-1200 -325) $PN 2
J 0
(-1238 -313);
DISPLAY 0.617021 (-1238 -313);
PAINT WHITE (-1238 -313);
FORCEPROP 1 LAST PATH I4
J 0
(-1350 -175);
DISPLAY 0.978723 (-1350 -175);
PAINT WHITE (-1350 -175);
DISPLAY INVISIBLE (-1350 -175);
FORCEPROP 0 LAST CDS_SEC 1
J 0
(-1350 -225);
PAINT MONO (-1350 -225);
DISPLAY INVISIBLE (-1350 -225);
FORCEPROP 2 LAST CDS_LIB mstr_discrete
J 0
(-1300 -325);
PAINT ORANGE (-1300 -325);
DISPLAY INVISIBLE (-1300 -325);
FORCEPROP 2 LAST SEC 1
J 0
(-1350 -125);
DISPLAY 0.680851 (-1350 -125);
PAINT MONO (-1350 -125);
DISPLAY INVISIBLE (-1350 -125);
FORCEPROP 2 LAST CDS_LOCATION R4A2
J 0
(-1350 -275);
DISPLAY 0.617021 (-1350 -275);
PAINT AQUA (-1350 -275);
DISPLAY INVISIBLE (-1350 -275);
FORCEPROP 2 LAST ROOM VTT_DEF_PWR_VR
J 0
(-1330 -170);
DISPLAY 1.021277 (-1330 -170);
PAINT ORANGE (-1330 -170);
DISPLAY INVISIBLE (-1330 -170);
FORCEPROP 2 LAST BOM_COST MEM_VRD_VTT_DEF
J 0
(-1330 -120);
DISPLAY 1.021277 (-1330 -120);
PAINT ORANGE (-1330 -120);
DISPLAY INVISIBLE (-1330 -120);
FORCEPROP 2 LAST SEC_TYPE 0402
J 0
(-1350 -125);
DISPLAY 1.021277 (-1350 -125);
PAINT ORANGE (-1350 -125);
DISPLAY INVISIBLE (-1350 -125);
FORCEADD CAP_A..1
(3500 2825);
FORCEPROP 0 LAST GROUP PWR_MLCC_CAP
J 0
(3556 2587);
DISPLAY 0.638298 (3556 2587);
PAINT BROWN (3556 2587);
DISPLAY BOTH (3556 2587);
FORCEPROP 1 LAST LOCATION C5M13
J 0
(3550 2925);
DISPLAY 0.617021 (3550 2925);
PAINT AQUA (3550 2925);
FORCEPROP 1 LAST PACK_TYPE 0603V
J 0
(3550 2625);
DISPLAY 0.617021 (3550 2625);
PAINT SKYBLUE (3550 2625);
FORCEPROP 1 LAST PART_NUMBER 602433-106
J 0
(3550 2675);
DISPLAY 0.617021 (3550 2675);
PAINT BLUE (3550 2675);
FORCEPROP 1 LAST MATERIAL X5R
J 0
(3550 2725);
DISPLAY 0.617021 (3550 2725);
PAINT SKYBLUE (3550 2725);
FORCEPROP 1 LAST TOLERANCE 20%
J 0
(3550 2775);
DISPLAY 0.617021 (3550 2775);
PAINT SKYBLUE (3550 2775);
FORCEPROP 1 LASTPIN (3500 2725) $PN 2
J 0
(3510 2705);
DISPLAY 0.617021 (3510 2705);
PAINT ORANGE (3510 2705);
FORCEPROP 1 LAST VALUE 47UF
J 0
(3550 2875);
DISPLAY 0.617021 (3550 2875);
PAINT SKYBLUE (3550 2875);
FORCEPROP 1 LASTPIN (3500 2925) $PN 1
J 0
(3510 2905);
DISPLAY 0.617021 (3510 2905);
PAINT ORANGE (3510 2905);
FORCEPROP 1 LAST VOLTAGE 4V
J 0
(3550 2825);
DISPLAY 0.617021 (3550 2825);
PAINT SKYBLUE (3550 2825);
FORCEPROP 1 LAST PATH I41
J 0
(3550 2975);
DISPLAY 0.978723 (3550 2975);
PAINT WHITE (3550 2975);
DISPLAY INVISIBLE (3550 2975);
FORCEPROP 2 LAST SEC 1
J 0
(3550 3025);
DISPLAY 0.680851 (3550 3025);
PAINT MONO (3550 3025);
DISPLAY INVISIBLE (3550 3025);
FORCEPROP 2 LAST CDS_SEC 1
J 0
(3550 2975);
PAINT ORANGE (3550 2975);
DISPLAY INVISIBLE (3550 2975);
FORCEPROP 2 LAST SEC_TYPE 0603V
J 0
(3550 3025);
DISPLAY 1.021277 (3550 3025);
PAINT ORANGE (3550 3025);
DISPLAY INVISIBLE (3550 3025);
FORCEPROP 2 LAST CDS_LOCATION C5M13
J 0
(3550 2925);
DISPLAY 0.617021 (3550 2925);
PAINT AQUA (3550 2925);
DISPLAY INVISIBLE (3550 2925);
FORCEPROP 2 LAST CDS_LIB dev_discrete
J 0
(3500 2825);
PAINT ORANGE (3500 2825);
DISPLAY INVISIBLE (3500 2825);
FORCEADD CAP..1
(3100 2825);
FORCEPROP 0 LAST GROUP PWR_MLCC_CAP
J 0
(3156 2412);
DISPLAY 0.638298 (3156 2412);
PAINT BROWN (3156 2412);
DISPLAY BOTH (3156 2412);
FORCEPROP 1 LAST PART_NUMBER 602433-112
J 0
(3150 2725);
DISPLAY 0.617021 (3150 2725);
PAINT BLUE (3150 2725);
FORCEPROP 1 LAST PACK_TYPE 0805
J 0
(3150 2675);
DISPLAY 0.617021 (3150 2675);
PAINT SKYBLUE (3150 2675);
FORCEPROP 1 LAST TOLERANCE 20%
J 0
(3150 2775);
DISPLAY 0.617021 (3150 2775);
PAINT SKYBLUE (3150 2775);
FORCEPROP 0 LAST NEW_MATERIAL X6S
J 0
(3150 2450);
DISPLAY 0.638298 (3150 2450);
PAINT BROWN (3150 2450);
DISPLAY BOTH (3150 2450);
FORCEPROP 1 LAST LOCATION C5L5
J 0
(3150 2925);
DISPLAY 0.617021 (3150 2925);
PAINT AQUA (3150 2925);
FORCEPROP 1 LAST VALUE 100UF
J 0
(3150 2875);
DISPLAY 0.617021 (3150 2875);
PAINT SKYBLUE (3150 2875);
FORCEPROP 1 LAST VOLTAGE 4V
J 0
(3150 2825);
DISPLAY 0.617021 (3150 2825);
PAINT SKYBLUE (3150 2825);
FORCEPROP 1 LASTPIN (3100 2725) $PN 2
J 0
(3110 2705);
DISPLAY 0.617021 (3110 2705);
PAINT ORANGE (3110 2705);
FORCEPROP 1 LASTPIN (3100 2925) $PN 1
J 0
(3110 2905);
DISPLAY 0.617021 (3110 2905);
PAINT ORANGE (3110 2905);
FORCEPROP 0 LAST NEW_PN 078.1071T.M002
J 0
(3147 2504);
DISPLAY 0.638298 (3147 2504);
PAINT BROWN (3147 2504);
DISPLAY BOTH (3147 2504);
FORCEPROP 2 LAST CDS_LOCATION C5L5
J 0
(3150 2925);
DISPLAY 0.617021 (3150 2925);
PAINT AQUA (3150 2925);
DISPLAY INVISIBLE (3150 2925);
FORCEPROP 1 LAST PATH I44
J 0
(3150 2975);
DISPLAY 0.978723 (3150 2975);
PAINT WHITE (3150 2975);
DISPLAY INVISIBLE (3150 2975);
FORCEPROP 1 LAST MATERIAL X5R
J 0
(3150 2725);
DISPLAY 0.617021 (3150 2725);
PAINT SKYBLUE (3150 2725);
DISPLAY INVISIBLE (3150 2725);
FORCEPROP 2 LAST SEC 1
J 0
(3150 3025);
DISPLAY 0.680851 (3150 3025);
PAINT MONO (3150 3025);
DISPLAY INVISIBLE (3150 3025);
FORCEPROP 2 LAST SEC_TYPE 0805
J 0
(3150 3025);
DISPLAY 1.021277 (3150 3025);
PAINT ORANGE (3150 3025);
DISPLAY INVISIBLE (3150 3025);
FORCEPROP 2 LAST ROOM VDDQ_ABC_PWR_VR
J 0
(3150 2975);
PAINT MONO (3150 2975);
DISPLAY INVISIBLE (3150 2975);
FORCEPROP 2 LAST BOM_COST MEM_VRD_PVDDQ_CD
J 0
(3150 2975);
PAINT MONO (3150 2975);
DISPLAY INVISIBLE (3150 2975);
FORCEPROP 2 LAST CDS_LIB mstr_discrete
J 0
(3100 2825);
PAINT MONO (3100 2825);
DISPLAY INVISIBLE (3100 2825);
FORCEPROP 0 LAST CDS_SEC 1
J 0
(3150 2975);
PAINT MONO (3150 2975);
DISPLAY INVISIBLE (3150 2975);
FORCEADD CAP..1
(2750 2825);
FORCEPROP 0 LAST GROUP PWR_MLCC_CAP
J 0
(2806 2537);
DISPLAY 0.638298 (2806 2537);
PAINT BROWN (2806 2537);
DISPLAY BOTH (2806 2537);
FORCEPROP 1 LAST PART_NUMBER 602433-112
J 0
(2800 2725);
DISPLAY 0.617021 (2800 2725);
PAINT BLUE (2800 2725);
FORCEPROP 0 LAST NEW_MATERIAL X6S
J 0
(2800 2575);
DISPLAY 0.638298 (2800 2575);
PAINT BROWN (2800 2575);
DISPLAY BOTH (2800 2575);
FORCEPROP 1 LASTPIN (2750 2725) $PN 2
J 0
(2760 2705);
DISPLAY 0.617021 (2760 2705);
PAINT ORANGE (2760 2705);
FORCEPROP 1 LAST LOCATION C5L4
J 0
(2800 2925);
DISPLAY 0.617021 (2800 2925);
PAINT AQUA (2800 2925);
FORCEPROP 1 LASTPIN (2750 2925) $PN 1
J 0
(2760 2905);
DISPLAY 0.617021 (2760 2905);
PAINT ORANGE (2760 2905);
FORCEPROP 1 LAST VALUE 100UF
J 0
(2800 2875);
DISPLAY 0.617021 (2800 2875);
PAINT SKYBLUE (2800 2875);
FORCEPROP 1 LAST VOLTAGE 4V
J 0
(2800 2825);
DISPLAY 0.617021 (2800 2825);
PAINT SKYBLUE (2800 2825);
FORCEPROP 1 LAST TOLERANCE 20%
J 0
(2800 2775);
DISPLAY 0.617021 (2800 2775);
PAINT SKYBLUE (2800 2775);
FORCEPROP 0 LAST NEW_PN 078.1071T.M002
J 0
(2797 2629);
DISPLAY 0.638298 (2797 2629);
PAINT BROWN (2797 2629);
DISPLAY BOTH (2797 2629);
FORCEPROP 1 LAST PACK_TYPE 0805
J 0
(2800 2675);
DISPLAY 0.617021 (2800 2675);
PAINT SKYBLUE (2800 2675);
FORCEPROP 2 LAST CDS_LOCATION C5L4
J 0
(2800 2925);
DISPLAY 0.617021 (2800 2925);
PAINT AQUA (2800 2925);
DISPLAY INVISIBLE (2800 2925);
FORCEPROP 1 LAST MATERIAL X5R
J 0
(2800 2725);
DISPLAY 0.617021 (2800 2725);
PAINT SKYBLUE (2800 2725);
DISPLAY INVISIBLE (2800 2725);
FORCEPROP 2 LAST SEC 1
J 0
(2800 3025);
DISPLAY 0.680851 (2800 3025);
PAINT MONO (2800 3025);
DISPLAY INVISIBLE (2800 3025);
FORCEPROP 2 LAST SEC_TYPE 0805
J 0
(2800 3025);
DISPLAY 1.021277 (2800 3025);
PAINT ORANGE (2800 3025);
DISPLAY INVISIBLE (2800 3025);
FORCEPROP 2 LAST ROOM VDDQ_ABC_PWR_VR
J 0
(2800 2975);
PAINT MONO (2800 2975);
DISPLAY INVISIBLE (2800 2975);
FORCEPROP 2 LAST BOM_COST MEM_VRD_PVDDQ_CD
J 0
(2800 2975);
PAINT MONO (2800 2975);
DISPLAY INVISIBLE (2800 2975);
FORCEPROP 2 LAST CDS_LIB mstr_discrete
J 0
(2750 2825);
PAINT MONO (2750 2825);
DISPLAY INVISIBLE (2750 2825);
FORCEPROP 0 LAST CDS_SEC 1
J 0
(2800 2975);
PAINT MONO (2800 2975);
DISPLAY INVISIBLE (2800 2975);
FORCEPROP 1 LAST PATH I45
J 0
(2800 2975);
DISPLAY 0.978723 (2800 2975);
PAINT WHITE (2800 2975);
DISPLAY INVISIBLE (2800 2975);
FORCEADD CAP..1
(4100 575);
FORCEPROP 1 LAST VOLTAGE 4V
J 0
(4150 575);
DISPLAY 0.617021 (4150 575);
PAINT SKYBLUE (4150 575);
FORCEPROP 1 LAST LOCATION C4W5
J 0
(4150 675);
DISPLAY 0.617021 (4150 675);
PAINT AQUA (4150 675);
FORCEPROP 1 LAST VALUE 100UF
J 0
(4150 625);
DISPLAY 0.617021 (4150 625);
PAINT SKYBLUE (4150 625);
FORCEPROP 1 LAST TOLERANCE 20%
J 0
(4150 525);
DISPLAY 0.617021 (4150 525);
PAINT SKYBLUE (4150 525);
FORCEPROP 1 LASTPIN (4100 475) $PN 2
J 0
(4110 455);
DISPLAY 0.617021 (4110 455);
PAINT ORANGE (4110 455);
FORCEPROP 1 LASTPIN (4100 675) $PN 1
J 0
(4110 655);
DISPLAY 0.617021 (4110 655);
PAINT ORANGE (4110 655);
FORCEPROP 1 LAST PART_NUMBER 602433-112
J 0
(4150 475);
DISPLAY 0.617021 (4150 475);
PAINT BLUE (4150 475);
FORCEPROP 1 LAST PACK_TYPE 0805
J 0
(4150 425);
DISPLAY 0.617021 (4150 425);
PAINT SKYBLUE (4150 425);
FORCEPROP 0 LAST GROUP PWR_MLCC_CAP
J 0
(4156 287);
DISPLAY 0.638298 (4156 287);
PAINT BROWN (4156 287);
DISPLAY BOTH (4156 287);
FORCEPROP 0 LAST NEW_MATERIAL X6S
J 0
(4150 325);
DISPLAY 0.638298 (4150 325);
PAINT BROWN (4150 325);
DISPLAY BOTH (4150 325);
FORCEPROP 0 LAST NEW_PN 078.1071T.M002
J 0
(4147 379);
DISPLAY 0.638298 (4147 379);
PAINT BROWN (4147 379);
DISPLAY BOTH (4147 379);
FORCEPROP 2 LAST CDS_LOCATION C4W5
J 0
(4150 675);
DISPLAY 0.617021 (4150 675);
PAINT AQUA (4150 675);
DISPLAY INVISIBLE (4150 675);
FORCEPROP 1 LAST PATH I46
J 0
(4150 725);
DISPLAY 0.978723 (4150 725);
PAINT WHITE (4150 725);
DISPLAY INVISIBLE (4150 725);
FORCEPROP 1 LAST MATERIAL X5R
J 0
(4150 475);
DISPLAY 0.617021 (4150 475);
PAINT SKYBLUE (4150 475);
DISPLAY INVISIBLE (4150 475);
FORCEPROP 2 LAST SEC 1
J 0
(4150 775);
DISPLAY 0.680851 (4150 775);
PAINT MONO (4150 775);
DISPLAY INVISIBLE (4150 775);
FORCEPROP 2 LAST SEC_TYPE 0805
J 0
(4150 775);
DISPLAY 1.021277 (4150 775);
PAINT ORANGE (4150 775);
DISPLAY INVISIBLE (4150 775);
FORCEPROP 2 LAST ROOM VDDQ_ABC_PWR_VR
J 0
(4150 725);
PAINT MONO (4150 725);
DISPLAY INVISIBLE (4150 725);
FORCEPROP 2 LAST BOM_COST MEM_VRD_PVDDQ_CD
J 0
(4150 725);
PAINT MONO (4150 725);
DISPLAY INVISIBLE (4150 725);
FORCEPROP 2 LAST CDS_LIB mstr_discrete
J 0
(4100 575);
PAINT MONO (4100 575);
DISPLAY INVISIBLE (4100 575);
FORCEPROP 0 LAST CDS_SEC 1
J 0
(4150 725);
PAINT MONO (4150 725);
DISPLAY INVISIBLE (4150 725);
FORCEADD RES..2
R 2
(-1100 200);
FORCEPROP 1 LAST PACK_TYPE 0402
J 2
(-1140 25);
DISPLAY 0.617021 (-1140 25);
PAINT SKYBLUE (-1140 25);
FORCEPROP 1 LAST PART_NUMBER G21796-021
J 2
(-1140 75);
DISPLAY 0.617021 (-1140 75);
PAINT BLUE (-1140 75);
FORCEPROP 1 LAST MATERIAL EMPTY
J 2
(-1140 125);
DISPLAY 0.617021 (-1140 125);
PAINT RED (-1140 125);
FORCEPROP 1 LAST WATTAGE 1/16W
J 2
(-1140 175);
DISPLAY 0.617021 (-1140 175);
PAINT SKYBLUE (-1140 175);
FORCEPROP 1 LAST TOLERANCE 1%
J 2
(-1145 225);
DISPLAY 0.617021 (-1145 225);
PAINT SKYBLUE (-1145 225);
FORCEPROP 1 LAST VALUE 1.0M
J 2
(-1145 275);
DISPLAY 0.617021 (-1145 275);
PAINT SKYBLUE (-1145 275);
FORCEPROP 1 LAST LOCATION R6L4
J 2
(-1145 325);
DISPLAY 0.617021 (-1145 325);
PAINT AQUA (-1145 325);
FORCEPROP 1 LASTPIN (-1100 100) $PN 2
J 2
(-1105 110);
DISPLAY 0.617021 (-1105 110);
PAINT WHITE (-1105 110);
FORCEPROP 1 LASTPIN (-1100 300) $PN 1
J 2
(-1105 262);
DISPLAY 0.617021 (-1105 262);
PAINT WHITE (-1105 262);
FORCEPROP 1 LAST PATH I5
J 2
(-1150 375);
DISPLAY 0.978723 (-1150 375);
PAINT WHITE (-1150 375);
DISPLAY INVISIBLE (-1150 375);
FORCEPROP 0 LAST CDS_SEC 1
J 0
(-1125 375);
PAINT MONO (-1125 375);
DISPLAY INVISIBLE (-1125 375);
FORCEPROP 2 LAST CDS_LIB mstr_discrete
J 0
(-1100 200);
PAINT ORANGE (-1100 200);
DISPLAY INVISIBLE (-1100 200);
FORCEPROP 2 LAST CDS_LOCATION R6L4
J 2
(-1145 325);
DISPLAY 0.617021 (-1145 325);
PAINT AQUA (-1145 325);
DISPLAY INVISIBLE (-1145 325);
FORCEPROP 2 LAST BOM_COST MEM_VRD_VTT_DEF
J 0
(-1135 415);
DISPLAY 1.021277 (-1135 415);
PAINT ORANGE (-1135 415);
DISPLAY INVISIBLE (-1135 415);
FORCEPROP 2 LAST SEC_TYPE 0402
J 0
(-1129 430);
DISPLAY 1.021277 (-1129 430);
PAINT ORANGE (-1129 430);
DISPLAY INVISIBLE (-1129 430);
FORCEPROP 2 LAST SEC 1
J 0
(-1129 430);
DISPLAY 0.680851 (-1129 430);
PAINT MONO (-1129 430);
DISPLAY INVISIBLE (-1129 430);
FORCEPROP 2 LAST ROOM VTT_DEF_PWR_VR
J 0
(-1135 365);
DISPLAY 1.021277 (-1135 365);
PAINT ORANGE (-1135 365);
DISPLAY INVISIBLE (-1135 365);
FORCEADD RES..2
R 1
(-1500 1100);
FORCEPROP 1 LAST PACK_TYPE 0402
J 0
(-1275 1040);
DISPLAY 0.617021 (-1275 1040);
PAINT SKYBLUE (-1275 1040);
FORCEPROP 1 LAST MATERIAL CHIP
J 0
(-1375 1140);
DISPLAY 0.808511 (-1375 1140);
PAINT SKYBLUE (-1375 1140);
FORCEPROP 1 LAST VALUE 0.0
J 0
(-1575 1045);
DISPLAY 0.617021 (-1575 1045);
PAINT SKYBLUE (-1575 1045);
FORCEPROP 1 LAST WATTAGE 1/16W
J 0
(-1475 1040);
DISPLAY 0.617021 (-1475 1040);
PAINT SKYBLUE (-1475 1040);
FORCEPROP 1 LAST TOLERANCE 5%
J 0
(-1650 1045);
DISPLAY 0.617021 (-1650 1045);
PAINT SKYBLUE (-1650 1045);
FORCEPROP 1 LAST LOCATION R6L10
J 0
(-1525 1145);
DISPLAY 0.617021 (-1525 1145);
PAINT AQUA (-1525 1145);
FORCEPROP 1 LAST PART_NUMBER G21497-005
J 0
(-1600 990);
DISPLAY 0.617021 (-1600 990);
PAINT BLUE (-1600 990);
FORCEPROP 1 LASTPIN (-1600 1100) $PN 1
R 1
J 0
(-1562 1105);
DISPLAY 0.617021 (-1562 1105);
PAINT WHITE (-1562 1105);
FORCEPROP 1 LASTPIN (-1400 1100) $PN 2
R 1
J 0
(-1410 1105);
DISPLAY 0.617021 (-1410 1105);
PAINT WHITE (-1410 1105);
FORCEPROP 1 LAST PATH I6
R 1
J 0
(-1675 1150);
DISPLAY 0.978723 (-1675 1150);
PAINT WHITE (-1675 1150);
DISPLAY INVISIBLE (-1675 1150);
FORCEPROP 0 LAST CDS_SEC 1
R 1
J 0
(-1525 1175);
PAINT MONO (-1525 1175);
DISPLAY INVISIBLE (-1525 1175);
FORCEPROP 2 LAST CDS_LIB mstr_discrete
R 1
J 0
(-1500 1100);
PAINT ORANGE (-1500 1100);
DISPLAY INVISIBLE (-1500 1100);
FORCEPROP 2 LAST CDS_LOCATION R6L10
J 0
(-1525 1145);
DISPLAY 0.617021 (-1525 1145);
PAINT AQUA (-1525 1145);
DISPLAY INVISIBLE (-1525 1145);
FORCEPROP 2 LAST SEC_TYPE 0402
J 0
(-1519 1190);
DISPLAY 1.021277 (-1519 1190);
PAINT ORANGE (-1519 1190);
DISPLAY INVISIBLE (-1519 1190);
FORCEPROP 2 LAST NO_XNET_CONNECTION 1
J 0
(-1525 1175);
PAINT MONO (-1525 1175);
DISPLAY INVISIBLE (-1525 1175);
FORCEPROP 2 LAST SEC 1
J 0
(-1519 1190);
DISPLAY 0.680851 (-1519 1190);
PAINT MONO (-1519 1190);
DISPLAY INVISIBLE (-1519 1190);
FORCEPROP 2 LAST ROOM VTT_DEF_PWR_VR
J 0
(-1525 1200);
DISPLAY 1.021277 (-1525 1200);
PAINT ORANGE (-1525 1200);
DISPLAY INVISIBLE (-1525 1200);
FORCEPROP 2 LAST BOM_COST MEM_VRD_VTT_DEF
J 0
(-1525 1250);
DISPLAY 1.021277 (-1525 1250);
PAINT ORANGE (-1525 1250);
DISPLAY INVISIBLE (-1525 1250);
FORCEADD P3V3..1
(-1375 1700);
FORCEPROP 3 LASTPIN (-1375 1650) SIG_NAME P3V3\g
J 0
(-1365 1660);
DISPLAY 0.659574 (-1365 1660);
PAINT MONO (-1365 1660);
DISPLAY INVISIBLE (-1365 1660);
FORCEPROP 1 LAST PATH I7
J 0
(-1330 1702);
DISPLAY 0.340426 (-1330 1702);
PAINT GREEN (-1330 1702);
DISPLAY INVISIBLE (-1330 1702);
FORCEPROP 1 LAST VOLTAGE 3.3V
J 0
(-1420 1657);
DISPLAY 0.340426 (-1420 1657);
PAINT SKYBLUE (-1420 1657);
DISPLAY INVISIBLE (-1420 1657);
FORCEPROP 1 LAST SIZE 1B
J 0
(-1330 1722);
DISPLAY 0.340426 (-1330 1722);
PAINT GREEN (-1330 1722);
DISPLAY INVISIBLE (-1330 1722);
FORCEPROP 2 LAST CDS_LIB mstr_symbols
J 0
(-1375 1700);
PAINT ORANGE (-1375 1700);
DISPLAY INVISIBLE (-1375 1700);
FORCEPROP 1 LAST BODY_TYPE PLUMBING
J 0
(-1420 1657);
DISPLAY 0.340426 (-1420 1657);
PAINT GREEN (-1420 1657);
DISPLAY INVISIBLE (-1420 1657);
FORCEPROP 1 LAST HDL_POWER P3V3
J 0
(-1700 1575);
DISPLAY 0.872340 (-1700 1575);
PAINT ORANGE (-1700 1575);
DISPLAY INVISIBLE (-1700 1575);
FORCEADD GND..1
(-675 325);
FORCEPROP 3 LASTPIN (-675 375) SIG_NAME GND\g
J 0
(-665 385);
DISPLAY 0.659574 (-665 385);
PAINT MONO (-665 385);
DISPLAY INVISIBLE (-665 385);
FORCEPROP 1 LAST PATH I8
J 0
(-600 325);
DISPLAY 0.872340 (-600 325);
PAINT AQUA (-600 325);
DISPLAY INVISIBLE (-600 325);
FORCEPROP 1 LAST VOLTAGE 0.0V
J 0
(-720 282);
DISPLAY 0.340426 (-720 282);
PAINT SKYBLUE (-720 282);
DISPLAY INVISIBLE (-720 282);
FORCEPROP 2 LAST CDS_LIB mstr_symbols
J 0
(-675 325);
PAINT ORANGE (-675 325);
DISPLAY INVISIBLE (-675 325);
FORCEPROP 1 LAST SIZE 1B
J 0
(-600 275);
DISPLAY 0.872340 (-600 275);
PAINT AQUA (-600 275);
DISPLAY INVISIBLE (-600 275);
FORCEPROP 1 LAST BODY_TYPE PLUMBING
J 0
(-720 282);
DISPLAY 0.340426 (-720 282);
PAINT GREEN (-720 282);
DISPLAY INVISIBLE (-720 282);
FORCEPROP 1 LAST HDL_POWER GND
J 0
(-675 475);
DISPLAY 0.872340 (-675 475);
PAINT GREEN (-675 475);
DISPLAY INVISIBLE (-675 475);
FORCEADD CAP..1
(-675 525);
FORCEPROP 1 LAST PACK_TYPE 0603
J 0
(-625 325);
DISPLAY 0.617021 (-625 325);
PAINT SKYBLUE (-625 325);
FORCEPROP 1 LAST PART_NUMBER E15431-003
J 0
(-625 375);
DISPLAY 0.617021 (-625 375);
PAINT BLUE (-625 375);
FORCEPROP 1 LAST MATERIAL X6S
J 0
(-625 425);
DISPLAY 0.617021 (-625 425);
PAINT SKYBLUE (-625 425);
FORCEPROP 1 LASTPIN (-675 425) $PN 2
J 0
(-665 405);
DISPLAY 0.617021 (-665 405);
PAINT ORANGE (-665 405);
FORCEPROP 1 LASTPIN (-675 625) $PN 1
J 0
(-665 605);
DISPLAY 0.617021 (-665 605);
PAINT ORANGE (-665 605);
FORCEPROP 1 LAST TOLERANCE 10%
J 0
(-625 475);
DISPLAY 0.617021 (-625 475);
PAINT SKYBLUE (-625 475);
FORCEPROP 1 LAST VOLTAGE 6.3V
J 0
(-625 525);
DISPLAY 0.617021 (-625 525);
PAINT SKYBLUE (-625 525);
FORCEPROP 1 LAST VALUE 4.7UF
J 0
(-625 575);
DISPLAY 0.617021 (-625 575);
PAINT SKYBLUE (-625 575);
FORCEPROP 1 LAST LOCATION C4A11
J 0
(-625 625);
DISPLAY 0.617021 (-625 625);
PAINT AQUA (-625 625);
FORCEPROP 1 LAST PATH I9
J 0
(-625 675);
DISPLAY 0.978723 (-625 675);
PAINT WHITE (-625 675);
DISPLAY INVISIBLE (-625 675);
FORCEPROP 0 LAST CDS_SEC 1
J 0
(-625 675);
PAINT MONO (-625 675);
DISPLAY INVISIBLE (-625 675);
FORCEPROP 2 LAST CDS_LIB mstr_discrete
J 0
(-675 525);
PAINT ORANGE (-675 525);
DISPLAY INVISIBLE (-675 525);
FORCEPROP 2 LAST CDS_LOCATION C4A11
J 0
(-625 625);
DISPLAY 0.617021 (-625 625);
PAINT AQUA (-625 625);
DISPLAY INVISIBLE (-625 625);
FORCEPROP 2 LAST SEC_TYPE 0603
J 0
(-625 725);
DISPLAY 1.021277 (-625 725);
PAINT ORANGE (-625 725);
DISPLAY INVISIBLE (-625 725);
FORCEPROP 2 LAST SEC 1
J 0
(-625 725);
DISPLAY 0.680851 (-625 725);
PAINT MONO (-625 725);
DISPLAY INVISIBLE (-625 725);
FORCEPROP 0 LAST ROOM VTT_DEF_PWR_VR
J 0
(-625 725);
DISPLAY 1.021277 (-625 725);
PAINT ORANGE (-625 725);
DISPLAY INVISIBLE (-625 725);
FORCEADD CAD_NOTE..1
(3975 -225);
FORCEPROP 0 LAST L1 SPOF
J 0
(3836 -374);
DISPLAY 0.617021 (3836 -374);
PAINT WHITE (3836 -374);
FORCEPROP 2 LAST CDS_LIB mstr_symbols
J 0
(3975 -225);
PAINT ORANGE (3975 -225);
DISPLAY INVISIBLE (3975 -225);
FORCEPROP 1 LAST COMMENT_BODY TRUE
J 0
(4000 -125);
DISPLAY 0.978723 (4000 -125);
PAINT ORANGE (4000 -125);
DISPLAY INVISIBLE (4000 -125);
FORCEADD INTEL_CORP_BPAGE..1
(5100 -1625);
FORCEPROP 1 LAST CDS_CON_LAST_MODIFIED Fri Jun 16 17:49:19 2017
J 0
(3675 -1300);
PAINT GREEN (3675 -1300);
DISPLAY INVISIBLE (3675 -1300);
FORCEPROP 1 LAST CUSTOM_TXT_CDS <CURRENT_DESIGN_SHEET> OF <TOTAL_DESIGN_SHEETS>
J 0
(4600 -1600);
PAINT ORANGE (4600 -1600);
FORCEPROP 1 LAST CUSTOM_TXT_CDS <CON_LAST_MODIFIED>
J 0
(1100 -1525);
PAINT ORANGE (1100 -1525);
FORCEPROP 2 LAST CUSTOM_TXT_CDS <XR_PAGE_TITLE>
J 0
(-2790 3625);
DISPLAY 0.638298 (-2790 3625);
PAINT PINK (-2790 3625);
DISPLAY INVISIBLE (-2790 3625);
FORCEPROP 1 LAST SCH_TITLE DDR VTT VR CHANNEL DEF
J 0
(-2850 -1575);
DISPLAY 1.212766 (-2850 -1575);
PAINT GREEN (-2850 -1575);
FORCEPROP 2 LAST CDS_XR_PAGE_TITLE CR-222 : @BASEBOARD_FAB2_LIB.BASEBOARD_FAB2(SCH_1):PAGE222
J 0
(-2790 3625);
DISPLAY 0.638298 (-2790 3625);
PAINT PINK (-2790 3625);
DISPLAY INVISIBLE (-2790 3625);
FORCEPROP 2 LAST PAGE_BORDER TRUE
J 0
(-2790 3625);
DISPLAY 0.659574 (-2790 3625);
PAINT PINK (-2790 3625);
DISPLAY INVISIBLE (-2790 3625);
FORCEPROP 2 LAST CDS_LIB mstr_symbols
J 0
(5100 -1625);
PAINT ORANGE (5100 -1625);
DISPLAY INVISIBLE (5100 -1625);
FORCEPROP 1 LAST COMMENT_BODY TRUE
J 0
(5112 -1613);
DISPLAY 0.446809 (5112 -1613);
PAINT GREEN (5112 -1613);
DISPLAY INVISIBLE (5112 -1613);
FORCEADD DNS..2
(-1145 -855);
PAINT RED (-1145 -855);
FORCEPROP 2 LAST CDS_LIB mstr_misc
J 0
(-1145 -855);
PAINT ORANGE (-1145 -855);
DISPLAY INVISIBLE (-1145 -855);
FORCEPROP 1 LAST COMMENT_BODY TRUE
R 1
J 0
(-1070 -1080);
DISPLAY 0.872340 (-1070 -1080);
PAINT GREEN (-1070 -1080);
DISPLAY INVISIBLE (-1070 -1080);
FORCEADD CAD_NOTE..1
(3950 -700);
FORCEPROP 0 LAST L2 OF PVTT PLANE
J 0
(3832 -847);
DISPLAY 0.617021 (3832 -847);
PAINT WHITE (3832 -847);
FORCEPROP 0 LAST L1 PLACE NEAR CENTER
J 0
(3832 -795);
DISPLAY 0.617021 (3832 -795);
PAINT WHITE (3832 -795);
FORCEPROP 2 LAST CDS_LIB mstr_symbols
J 0
(3950 -700);
PAINT ORANGE (3950 -700);
DISPLAY INVISIBLE (3950 -700);
FORCEPROP 1 LAST COMMENT_BODY TRUE
J 0
(3975 -600);
DISPLAY 0.978723 (3975 -600);
PAINT ORANGE (3975 -600);
DISPLAY INVISIBLE (3975 -600);
FORCEADD CAD_NOTE..1
(-675 2300);
FORCEPROP 0 LAST L1 PLACE CLOSE TO CONTROLLER
J 0
(-762 2208);
DISPLAY 0.617021 (-762 2208);
PAINT WHITE (-762 2208);
FORCEPROP 2 LAST CDS_LIB mstr_symbols
J 0
(-675 2300);
PAINT ORANGE (-675 2300);
DISPLAY INVISIBLE (-675 2300);
FORCEPROP 1 LAST COMMENT_BODY TRUE
J 0
(-650 2400);
DISPLAY 0.978723 (-650 2400);
PAINT ORANGE (-650 2400);
DISPLAY INVISIBLE (-650 2400);
FORCEADD CAD_NOTE..1
(3950 3150);
FORCEPROP 2 LAST CDS_LIB mstr_symbols
J 0
(3950 3150);
PAINT ORANGE (3950 3150);
DISPLAY INVISIBLE (3950 3150);
FORCEPROP 1 LAST COMMENT_BODY TRUE
J 0
(3975 3250);
DISPLAY 0.978723 (3975 3250);
PAINT ORANGE (3975 3250);
DISPLAY INVISIBLE (3975 3250);
FORCEADD CAD_NOTE..1
(1475 1125);
FORCEPROP 0 LAST L1 PLACE CLOSE TO CONTROLLER
J 0
(1293 1033);
DISPLAY 0.617021 (1293 1033);
PAINT WHITE (1293 1033);
FORCEPROP 2 LAST CDS_LIB mstr_symbols
J 0
(1475 1125);
PAINT ORANGE (1475 1125);
DISPLAY INVISIBLE (1475 1125);
FORCEPROP 1 LAST COMMENT_BODY TRUE
J 0
(1500 1225);
DISPLAY 0.978723 (1500 1225);
PAINT ORANGE (1500 1225);
DISPLAY INVISIBLE (1500 1225);
FORCEADD DNS..3
(4180 -430);
PAINT RED (4180 -430);
FORCEPROP 2 LAST CDS_LIB mstr_misc
J 0
(4180 -430);
PAINT ORANGE (4180 -430);
DISPLAY INVISIBLE (4180 -430);
FORCEPROP 1 LAST COMMENT_BODY TRUE
R 1
J 0
(4255 -655);
DISPLAY 0.872340 (4255 -655);
PAINT GREEN (4255 -655);
DISPLAY INVISIBLE (4255 -655);
FORCEADD PRELIM..6
(760 590);
PAINT GRAY (760 590);
FORCEPROP 2 LAST CDS_LIB mstr_misc
J 0
(760 590);
PAINT ORANGE (760 590);
DISPLAY INVISIBLE (760 590);
FORCEPROP 1 LAST COMMENT_BODY TRUE
J 0
(760 590);
PAINT ORANGE (760 590);
DISPLAY INVISIBLE (760 590);
FORCEADD DNS..2
(-1095 195);
PAINT RED (-1095 195);
FORCEPROP 2 LAST CDS_LIB mstr_misc
J 0
(-1095 195);
PAINT ORANGE (-1095 195);
DISPLAY INVISIBLE (-1095 195);
FORCEPROP 1 LAST COMMENT_BODY TRUE
R 1
J 0
(-1020 -30);
DISPLAY 0.872340 (-1020 -30);
PAINT GREEN (-1020 -30);
DISPLAY INVISIBLE (-1020 -30);
WIRE 16 -1 (-1150 -1025)(-1150 -950);
WIRE 16 -1 (-325 950)(-325 850);
WIRE 16 -1 (-750 1800)(-750 1700);
WIRE 16 -1 (-325 1700)(-325 1825);
WIRE 16 -1 (1225 300)(1225 175);
WIRE 16 -1 (1225 400)(1225 300);
WIRE 16 -1 (1075 300)(1225 300);
WIRE 16 -1 (1225 450)(1225 400);
WIRE 16 -1 (1075 400)(1225 400);
WIRE 16 -1 (1075 450)(1225 450);
WIRE 16 -1 (1625 175)(1625 300);
WIRE 16 -1 (3075 975)(3075 1075);
WIRE 16 -1 (2500 1825)(2500 1750);
WIRE 16 -1 (2750 3100)(2750 3150);
WIRE 16 -1 (2750 3100)(3100 3100);
WIRE 16 -1 (2750 3100)(2750 2925);
WIRE 16 -1 (3500 3100)(3100 3100);
WIRE 16 -1 (3100 2925)(3100 3100);
WIRE 16 -1 (3500 2925)(3500 3100);
WIRE 16 -1 (3200 225)(3200 325);
WIRE 16 -1 (4100 325)(3200 325);
WIRE 16 -1 (3200 325)(3200 475);
WIRE 16 -1 (4100 475)(4100 325);
WIRE 16 -1 (4750 1075)(4750 850);
WIRE 16 -1 (4750 850)(4100 850);
WIRE 16 -1 (4750 -425)(4750 850);
WIRE 16 -1 (4325 -425)(4750 -425);
WIRE 16 -1 (4100 850)(3200 850);
WIRE 16 -1 (4100 675)(4100 850);
WIRE 16 -1 (3200 675)(3200 850);
WIRE 16 -1 (1075 850)(3200 850);
WIRE 16 -1 (2750 2325)(2750 2350);
WIRE 16 -1 (2750 2350)(3100 2350);
WIRE 16 -1 (2750 2725)(2750 2350);
WIRE 16 -1 (3100 2350)(3500 2350);
WIRE 16 -1 (3100 2725)(3100 2350);
WIRE 16 -1 (3500 2725)(3500 2350);
WIRE 16 -1 (-2225 2275)(-2225 2075);
WIRE 16 -1 (-1775 2075)(-2225 2075);
WIRE 16 -1 (-1775 2075)(-1775 1100);
WIRE 16 -1 (-750 2075)(-1775 2075);
WIRE 16 -1 (-750 2075)(-325 2075);
WIRE 16 -1 (-750 2000)(-750 2075);
WIRE 16 -1 (-1600 1100)(-1775 1100);
WIRE 16 -1 (-325 2075)(300 2075);
WIRE 16 -1 (-325 2025)(-325 2075);
WIRE 16 -1 (300 850)(300 2075);
WIRE 16 -1 (475 850)(300 850);
WIRE 16 -1 (-1375 1650)(-1375 1300);
WIRE 16 -1 (-1100 1300)(-1375 1300);
WIRE 16 -1 (-750 1300)(-1100 1300);
WIRE 16 -1 (-1100 300)(-1100 1300);
WIRE 16 -1 (-675 375)(-675 425);
WIRE 3 682 (4050 225)(4050 775);
WIRE 3 682 (4700 225)(4050 225);
WIRE 3 682 (4050 775)(4700 775);
WIRE 3 682 (4700 775)(4700 225);
WIRE 16 2175 (2600 2200)(2600 3325);
WIRE 16 2175 (5050 3325)(2600 3325);
WIRE 16 2175 (5050 2200)(2600 2200);
WIRE 16 2175 (5050 2200)(5050 3325);
WIRE 16 -1 (475 350)(225 350);
WIRE 16 -1 (225 350)(225 1300);
WIRE 16 -1 (-325 1150)(-325 1300);
WIRE 16 -1 (225 1300)(-325 1300);
WIRE 16 -1 (-550 1300)(-325 1300);
FORCEPROP 2 LAST SIG_NAME VR_PVTT_DEF_BIAS
J 0
(-480 1320);
DISPLAY 0.617021 (-480 1320);
PAINT ORANGE (-480 1320);
FORCEPROP 2 LASTPROP $XRERR UNIQUE?
J 0
(-720 1320);
DISPLAY 0.638298 (-720 1320);
PAINT MONO (-720 1320);
DISPLAY INVISIBLE (-720 1320);
WIRE 3 682 (2700 3000)(2700 2250);
WIRE 3 682 (3450 3000)(2700 3000);
WIRE 3 682 (2700 2250)(3450 2250);
WIRE 3 682 (3450 2250)(3450 3000);
WIRE 16 -1 (475 500)(25 500);
WIRE 16 -1 (25 500)(25 -425);
WIRE 16 -1 (4025 -425)(25 -425);
FORCEPROP 2 LAST SIG_NAME VR_PVTT_DEF_SNS
J 0
(65 -420);
DISPLAY 0.617021 (65 -420);
PAINT ORANGE (65 -420);
FORCEPROP 2 LASTPROP $XRERR UNIQUE?
J 0
(-175 -420);
DISPLAY 0.638298 (-175 -420);
PAINT MONO (-175 -420);
DISPLAY INVISIBLE (-175 -420);
WIRE 16 2175 (-825 2375)(100 2375);
WIRE 16 2175 (100 775)(100 2375);
WIRE 16 2175 (-825 775)(-825 2375);
WIRE 16 2175 (-825 775)(100 775);
WIRE 16 273 (1525 2625)(375 2625);
WIRE 16 273 (375 2625)(375 3125);
WIRE 16 273 (1525 3125)(1525 2625);
WIRE 16 273 (375 3125)(1525 3125);
WIRE 16 273 (1525 3225)(1525 3125);
WIRE 16 273 (375 3125)(375 3225);
WIRE 16 273 (375 3225)(1525 3225);
WIRE 16 -1 (1075 550)(2500 550);
WIRE 16 -1 (2500 550)(2500 1375);
WIRE 16 -1 (2500 1550)(2500 1375);
WIRE 16 -1 (3075 1375)(2500 1375);
FORCEPROP 2 LAST SIG_NAME PWRGD_PVTT_DEF_CPU0_R
J 0
(2575 1385);
DISPLAY 0.617021 (2575 1385);
PAINT ORANGE (2575 1385);
FORCEPROP 2 LASTPROP $XRERR UNIQUE?
J 0
(2335 1385);
DISPLAY 0.638298 (2335 1385);
PAINT MONO (2335 1385);
DISPLAY INVISIBLE (2335 1385);
WIRE 16 -1 (3075 1275)(3075 1375);
WIRE 16 -1 (3375 1375)(3075 1375);
WIRE 16 -1 (4550 1375)(3575 1375);
FORCEPROP 2 LAST SIG_NAME PWRGD_PVTT_CPU0
J 0
(4000 1385);
DISPLAY 0.617021 (4000 1385);
PAINT ORANGE (4000 1385);
WIRE 16 -1 (-1150 -750)(-1150 -325);
WIRE 16 -1 (-1200 -325)(-1150 -325);
WIRE 16 -1 (-1100 -325)(-1150 -325);
WIRE 16 -1 (-1100 -325)(-1100 100);
WIRE 16 -1 (-200 -325)(-1100 -325);
WIRE 16 -1 (-200 600)(-200 -325);
WIRE 16 -1 (475 600)(-200 600);
FORCEPROP 2 LAST SIG_NAME FM_PVTT_DEF_EN_R
J 0
(-801 -310);
DISPLAY 0.617021 (-801 -310);
PAINT ORANGE (-801 -310);
FORCEPROP 2 LASTPROP $XRERR UNIQUE?
J 0
(-1041 -310);
DISPLAY 0.638298 (-1041 -310);
PAINT MONO (-1041 -310);
DISPLAY INVISIBLE (-1041 -310);
WIRE 16 2175 (3775 -900)(4425 -900);
WIRE 16 2175 (4425 -900)(4425 -300);
WIRE 16 2175 (3775 -900)(3775 -300);
WIRE 16 2175 (3775 -300)(4425 -300);
WIRE 16 -1 (-1275 1100)(-1400 1100);
WIRE 16 -1 (-1275 700)(-1275 1100);
WIRE 16 -1 (-675 700)(-1275 700);
WIRE 16 -1 (-675 625)(-675 700);
WIRE 16 -1 (475 700)(-675 700);
FORCEPROP 2 LAST SIG_NAME VSENSE_PVDDQ_DEF_VTT
J 0
(-470 710);
DISPLAY 0.617021 (-470 710);
PAINT ORANGE (-470 710);
FORCEPROP 2 LASTPROP $XRERR UNIQUE?
J 0
(-710 710);
DISPLAY 0.638298 (-710 710);
PAINT MONO (-710 710);
DISPLAY INVISIBLE (-710 710);
WIRE 16 2175 (1275 75)(1275 1200);
WIRE 16 2175 (2075 75)(1275 75);
WIRE 16 2175 (1275 1200)(2075 1200);
WIRE 16 2175 (2075 1200)(2075 75);
WIRE 3 682 (-2700 -400)(-2700 -250);
WIRE 3 682 (-1625 -400)(-2700 -400);
WIRE 3 682 (-2700 -250)(-1625 -250);
WIRE 3 682 (-1625 -250)(-1625 -400);
WIRE 16 -1 (-1400 -325)(-2150 -325);
FORCEPROP 2 LAST SIG_NAME PWRGD_PVDDQ_DEF_R
J 0
(-2100 -310);
DISPLAY 0.617021 (-2100 -310);
PAINT ORANGE (-2100 -310);
WIRE 16 -1 (1625 500)(1625 750);
WIRE 16 -1 (1075 750)(1625 750);
FORCEPROP 2 LAST SIG_NAME VR_PVTT_DEF_VREF
J 0
(1181 760);
DISPLAY 0.617021 (1181 760);
PAINT ORANGE (1181 760);
FORCEPROP 2 LASTPROP $XRERR UNIQUE?
J 0
(941 760);
DISPLAY 0.638298 (941 760);
PAINT MONO (941 760);
DISPLAY INVISIBLE (941 760);
DOT 1 (3100 2350);
DOT 1 (-325 1300);
DOT 1 (-750 2075);
DOT 1 (3075 1375);
DOT 1 (-1100 -325);
DOT 1 (-1150 -325);
DOT 1 (-1100 1300);
DOT 1 (-1775 2075);
DOT 1 (-675 700);
DOT 1 (-325 2075);
DOT 1 (375 3125);
DOT 1 (1225 300);
DOT 1 (1225 400);
DOT 1 (2500 1375);
DOT 1 (1525 3125);
DOT 1 (3200 325);
DOT 1 (3200 850);
DOT 1 (4100 850);
DOT 1 (2750 3100);
DOT 1 (2750 2350);
DOT 1 (3100 3100);
DOT 1 (4750 850);
FORCENOTE
TP FAB1 CHANGE RES TO CAP 0311
(3775 -25) 0;
DISPLAY LEFT (3775 -25);
DISPLAY 1.021277 (3775 -25);
PAINT RED (3775 -25);
FORCENOTE
TP FAB1 CHANGE CONNECTION 0303
(-2700 -225) 0;
DISPLAY LEFT (-2700 -225);
DISPLAY 1.021277 (-2700 -225);
PAINT RED (-2700 -225);
FORCENOTE
CRTICAL: PLACE 0 OHM NEAR  VDDQ SENSE RESISTOR.
(-2593 934) 0;
DISPLAY LEFT (-2593 934);
DISPLAY 1.021277 (-2593 934);
PAINT PURPLE (-2593 934);
FORCENOTE
BOM_COST = MEM_VRD_VTT_DEF
(-2855 -1451) 0;
DISPLAY LEFT (-2855 -1451);
DISPLAY 1.255319 (-2855 -1451);
PAINT PURPLE (-2855 -1451);
FORCENOTE
ROOM = VTT_DEF_PWR_VR
(-2855 -1376) 0;
DISPLAY LEFT (-2855 -1376);
DISPLAY 1.255319 (-2855 -1376);
PAINT PURPLE (-2855 -1376);
FORCENOTE
DC TOL= +/-1.5%
(418 2949) 0;
DISPLAY LEFT (418 2949);
DISPLAY 0.808511 (418 2949);
PAINT PURPLE (418 2949);
FORCENOTE
VOUT=0.5 VDDQ
(418 3049) 0;
DISPLAY LEFT (418 3049);
DISPLAY 0.808511 (418 3049);
PAINT PURPLE (418 3049);
FORCENOTE
PVTT DDR SPECIFICATION:
(418 3149) 0;
DISPLAY LEFT (418 3149);
PAINT PURPLE (418 3149);
FORCENOTE
IOUT DI/DT=6A/US
(418 2699) 0;
DISPLAY LEFT (418 2699);
DISPLAY 0.808511 (418 2699);
PAINT PURPLE (418 2699);
FORCENOTE
IOUT STEP=+ 1.523A / -1.546A
(418 2749) 0;
DISPLAY LEFT (418 2749);
DISPLAY 0.808511 (418 2749);
PAINT PURPLE (418 2749);
FORCENOTE
AC & RIPPLE=+3.5/-7.3%
(418 2899) 0;
DISPLAY LEFT (418 2899);
DISPLAY 0.808511 (418 2899);
PAINT PURPLE (418 2899);
FORCENOTE
RIPPLE GUIDELINE= +/-1%
(418 2999) 0;
DISPLAY LEFT (418 2999);
DISPLAY 0.808511 (418 2999);
PAINT PURPLE (418 2999);
FORCENOTE
IOUT PEAK=+-/1.4A
(418 2849) 0;
DISPLAY LEFT (418 2849);
DISPLAY 0.808511 (418 2849);
PAINT PURPLE (418 2849);
FORCENOTE
IOUT TDC=+/-1.4A
(418 2799) 0;
DISPLAY LEFT (418 2799);
DISPLAY 0.808511 (418 2799);
PAINT PURPLE (418 2799);
FORCENOTE
TP FAB3 CHANGE CAP 0803
(2700 2100) 0;
DISPLAY LEFT (2700 2100);
DISPLAY 1.021277 (2700 2100);
PAINT RED (2700 2100);
FORCENOTE
PLACE BETWEEN DIMMS
(3821 3012) 0;
DISPLAY LEFT (3821 3012);
DISPLAY 1.021277 (3821 3012);
PAINT PURPLE (3821 3012);
QUIT
